FILE_TYPE = MACRO_DRAWING;
SET COLOR_WIRE YELLOW;
SET COLOR_PROP MONO;
SET COLOR_DOT WHITE;
SET COLOR_ARC YELLOW;
SET COLOR_BODY GREEN;
SET COLOR_NOTE MONO;
SET PROP_DISPLAY VALUE;
SET PAGE_NUMBER P150;
FORCEADD CAP..1
(-2750 1300);
FORCEPROP 1 LAST PART_NUMBER D97712-004
R 1
J 0
(-2800 1100);
DISPLAY 0.617021 (-2800 1100);
PAINT BLUE (-2800 1100);
FORCEPROP 1 LAST LOCATION C25W60
J 0
(-2700 1400);
DISPLAY 0.617021 (-2700 1400);
PAINT AQUA (-2700 1400);
FORCEPROP 1 LAST VALUE 1.0UF
J 0
(-2700 1325);
DISPLAY 0.617021 (-2700 1325);
PAINT SKYBLUE (-2700 1325);
FORCEPROP 1 LAST VOLTAGE 6.3V
J 0
(-2700 1250);
DISPLAY 0.617021 (-2700 1250);
PAINT SKYBLUE (-2700 1250);
FORCEPROP 1 LAST TOLERANCE 10%
J 0
(-2700 1200);
DISPLAY 0.617021 (-2700 1200);
PAINT SKYBLUE (-2700 1200);
FORCEPROP 1 LAST MATERIAL X6S
J 0
(-2700 1150);
DISPLAY 0.617021 (-2700 1150);
PAINT SKYBLUE (-2700 1150);
FORCEPROP 1 LAST PACK_TYPE 0402
J 0
(-2700 1100);
DISPLAY 0.617021 (-2700 1100);
PAINT SKYBLUE (-2700 1100);
FORCEPROP 1 LAST PATH I1
J 0
(-2700 1450);
DISPLAY 0.978723 (-2700 1450);
PAINT WHITE (-2700 1450);
DISPLAY INVISIBLE (-2700 1450);
FORCEPROP 2 LAST CDS_LIB mstr_discrete
J 0
(-2750 1300);
PAINT MONO (-2750 1300);
DISPLAY INVISIBLE (-2750 1300);
FORCEPROP 2 LAST ROOM BMC
J 0
(-2700 1450);
DISPLAY 1.510638 (-2700 1450);
PAINT ORANGE (-2700 1450);
DISPLAY INVISIBLE (-2700 1450);
FORCEPROP 2 LAST BOM_COST SM_CONTROLLER
J 0
(-2700 1450);
PAINT MONO (-2700 1450);
DISPLAY INVISIBLE (-2700 1450);
FORCEPROP 1 LASTPIN (-2750 1200) $PN 2
J 0
(-2740 1180);
DISPLAY 0.787234 (-2740 1180);
PAINT ORANGE (-2740 1180);
DISPLAY INVISIBLE (-2740 1180);
FORCEPROP 1 LASTPIN (-2750 1400) $PN 1
J 0
(-2740 1380);
DISPLAY 0.787234 (-2740 1380);
PAINT ORANGE (-2740 1380);
DISPLAY INVISIBLE (-2740 1380);
FORCEADD SCD1U16V2KX-3GP..1
(775 2500);
FORCEPROP 1 LAST VALUE SCD1U16V2KX-3GP
J 0
(800 2450);
DISPLAY 0.617021 (800 2450);
PAINT GREEN (800 2450);
FORCEPROP 1 LAST LOCATION C25W55
J 0
(800 2530);
DISPLAY 0.617021 (800 2530);
PAINT GREEN (800 2530);
FORCEPROP 1 LAST PATH I10
J 0
(775 2500);
DISPLAY 0.617021 (775 2500);
PAINT GREEN (775 2500);
DISPLAY INVISIBLE (775 2500);
FORCEPROP 2 LAST CDS_LIB w_hdl
J 0
(775 2500);
PAINT MONO (775 2500);
DISPLAY INVISIBLE (775 2500);
FORCEPROP 1 LAST CDS_LMAN_SYM_OUTLINE -50,25,50,-25
J 0
(775 2500);
DISPLAY 0.468085 (775 2500);
PAINT GREEN (775 2500);
DISPLAY INVISIBLE (775 2500);
FORCEPROP 1 LAST PACK_TYPE SMD-BCG
J 0
(775 2500);
DISPLAY 0.617021 (775 2500);
PAINT GREEN (775 2500);
DISPLAY INVISIBLE (775 2500);
FORCEPROP 1 LAST PART_NUMBER 78.10421.2FL
J 0
(775 2500);
DISPLAY 0.617021 (775 2500);
PAINT GREEN (775 2500);
DISPLAY INVISIBLE (775 2500);
FORCEADD GND..1
(775 2075);
FORCEPROP 3 LASTPIN (775 2125) SIG_NAME GND\g
J 0
(785 2135);
DISPLAY 0.659574 (785 2135);
PAINT MONO (785 2135);
DISPLAY INVISIBLE (785 2135);
FORCEPROP 1 LAST PATH I11
J 0
(850 2075);
DISPLAY 0.872340 (850 2075);
PAINT AQUA (850 2075);
DISPLAY INVISIBLE (850 2075);
FORCEPROP 1 LAST VOLTAGE 0.0V
J 0
(730 2032);
DISPLAY 0.340426 (730 2032);
PAINT GREEN (730 2032);
DISPLAY INVISIBLE (730 2032);
FORCEPROP 1 LAST BODY_TYPE PLUMBING
J 0
(730 2032);
DISPLAY 0.340426 (730 2032);
PAINT GREEN (730 2032);
DISPLAY INVISIBLE (730 2032);
FORCEPROP 1 LAST SIZE 1B
J 0
(850 2025);
DISPLAY 0.872340 (850 2025);
PAINT AQUA (850 2025);
DISPLAY INVISIBLE (850 2025);
FORCEPROP 1 LAST HDL_POWER GND
J 0
(775 2225);
DISPLAY 0.872340 (775 2225);
PAINT GREEN (775 2225);
DISPLAY INVISIBLE (775 2225);
FORCEPROP 2 LAST CDS_LIB mstr_symbols
J 0
(775 2075);
PAINT MONO (775 2075);
DISPLAY INVISIBLE (775 2075);
FORCEADD CAP..1
(525 2475);
FORCEPROP 1 LAST VALUE 1.0UF
J 0
(575 2500);
DISPLAY 0.617021 (575 2500);
PAINT SKYBLUE (575 2500);
FORCEPROP 1 LAST MATERIAL X6S
J 0
(575 2325);
DISPLAY 0.617021 (575 2325);
PAINT SKYBLUE (575 2325);
FORCEPROP 1 LAST TOLERANCE 10%
J 0
(575 2375);
DISPLAY 0.617021 (575 2375);
PAINT SKYBLUE (575 2375);
FORCEPROP 1 LAST PART_NUMBER D97712-004
R 1
J 0
(475 2275);
DISPLAY 0.617021 (475 2275);
PAINT BLUE (475 2275);
FORCEPROP 1 LAST VOLTAGE 6.3V
J 0
(575 2425);
DISPLAY 0.617021 (575 2425);
PAINT SKYBLUE (575 2425);
FORCEPROP 1 LAST PACK_TYPE 0402
J 0
(575 2275);
DISPLAY 0.617021 (575 2275);
PAINT SKYBLUE (575 2275);
FORCEPROP 1 LAST LOCATION C25W54
J 0
(575 2575);
DISPLAY 0.617021 (575 2575);
PAINT AQUA (575 2575);
FORCEPROP 1 LAST PATH I12
J 0
(575 2625);
DISPLAY 0.978723 (575 2625);
PAINT WHITE (575 2625);
DISPLAY INVISIBLE (575 2625);
FORCEPROP 2 LAST ROOM BMC
J 0
(575 2625);
DISPLAY 1.510638 (575 2625);
PAINT ORANGE (575 2625);
DISPLAY INVISIBLE (575 2625);
FORCEPROP 2 LAST BOM_COST SM_CONTROLLER
J 0
(575 2625);
PAINT MONO (575 2625);
DISPLAY INVISIBLE (575 2625);
FORCEPROP 2 LAST CDS_LIB mstr_discrete
J 0
(525 2475);
PAINT MONO (525 2475);
DISPLAY INVISIBLE (525 2475);
FORCEPROP 1 LASTPIN (525 2375) $PN 2
J 0
(535 2355);
DISPLAY 0.787234 (535 2355);
PAINT ORANGE (535 2355);
DISPLAY INVISIBLE (535 2355);
FORCEPROP 1 LASTPIN (525 2575) $PN 1
J 0
(535 2555);
DISPLAY 0.787234 (535 2555);
PAINT ORANGE (535 2555);
DISPLAY INVISIBLE (535 2555);
FORCEADD CAP..1
(275 2475);
FORCEPROP 1 LAST VOLTAGE 6.3V
J 0
(325 2425);
DISPLAY 0.617021 (325 2425);
PAINT SKYBLUE (325 2425);
FORCEPROP 1 LAST LOCATION C25W53
J 0
(325 2575);
DISPLAY 0.617021 (325 2575);
PAINT AQUA (325 2575);
FORCEPROP 1 LAST VALUE 1.0UF
J 0
(325 2500);
DISPLAY 0.617021 (325 2500);
PAINT SKYBLUE (325 2500);
FORCEPROP 1 LAST TOLERANCE 10%
J 0
(325 2375);
DISPLAY 0.617021 (325 2375);
PAINT SKYBLUE (325 2375);
FORCEPROP 1 LAST MATERIAL X6S
J 0
(325 2325);
DISPLAY 0.617021 (325 2325);
PAINT SKYBLUE (325 2325);
FORCEPROP 1 LAST PART_NUMBER D97712-004
R 1
J 0
(225 2275);
DISPLAY 0.617021 (225 2275);
PAINT BLUE (225 2275);
FORCEPROP 1 LAST PACK_TYPE 0402
J 0
(325 2275);
DISPLAY 0.617021 (325 2275);
PAINT SKYBLUE (325 2275);
FORCEPROP 1 LAST PATH I13
J 0
(325 2625);
DISPLAY 0.978723 (325 2625);
PAINT WHITE (325 2625);
DISPLAY INVISIBLE (325 2625);
FORCEPROP 2 LAST ROOM BMC
J 0
(325 2625);
DISPLAY 1.510638 (325 2625);
PAINT ORANGE (325 2625);
DISPLAY INVISIBLE (325 2625);
FORCEPROP 2 LAST BOM_COST SM_CONTROLLER
J 0
(325 2625);
PAINT MONO (325 2625);
DISPLAY INVISIBLE (325 2625);
FORCEPROP 2 LAST CDS_LIB mstr_discrete
J 0
(275 2475);
PAINT MONO (275 2475);
DISPLAY INVISIBLE (275 2475);
FORCEPROP 1 LASTPIN (275 2375) $PN 2
J 0
(285 2355);
DISPLAY 0.787234 (285 2355);
PAINT ORANGE (285 2355);
DISPLAY INVISIBLE (285 2355);
FORCEPROP 1 LASTPIN (275 2575) $PN 1
J 0
(285 2555);
DISPLAY 0.787234 (285 2555);
PAINT ORANGE (285 2555);
DISPLAY INVISIBLE (285 2555);
FORCEADD CAP..1
(25 2475);
FORCEPROP 1 LAST LOCATION C25W52
J 0
(75 2575);
DISPLAY 0.617021 (75 2575);
PAINT AQUA (75 2575);
FORCEPROP 1 LAST VALUE 1.0UF
J 0
(75 2500);
DISPLAY 0.617021 (75 2500);
PAINT SKYBLUE (75 2500);
FORCEPROP 1 LAST VOLTAGE 6.3V
J 0
(75 2425);
DISPLAY 0.617021 (75 2425);
PAINT SKYBLUE (75 2425);
FORCEPROP 1 LAST PACK_TYPE 0402
J 0
(75 2275);
DISPLAY 0.617021 (75 2275);
PAINT SKYBLUE (75 2275);
FORCEPROP 1 LAST MATERIAL X6S
J 0
(75 2325);
DISPLAY 0.617021 (75 2325);
PAINT SKYBLUE (75 2325);
FORCEPROP 1 LAST TOLERANCE 10%
J 0
(75 2375);
DISPLAY 0.617021 (75 2375);
PAINT SKYBLUE (75 2375);
FORCEPROP 1 LAST PART_NUMBER D97712-004
R 1
J 0
(-25 2275);
DISPLAY 0.617021 (-25 2275);
PAINT BLUE (-25 2275);
FORCEPROP 1 LAST PATH I14
J 0
(75 2625);
DISPLAY 0.978723 (75 2625);
PAINT WHITE (75 2625);
DISPLAY INVISIBLE (75 2625);
FORCEPROP 2 LAST CDS_LIB mstr_discrete
J 0
(25 2475);
PAINT MONO (25 2475);
DISPLAY INVISIBLE (25 2475);
FORCEPROP 2 LAST BOM_COST SM_CONTROLLER
J 0
(75 2625);
PAINT MONO (75 2625);
DISPLAY INVISIBLE (75 2625);
FORCEPROP 2 LAST ROOM BMC
J 0
(75 2625);
DISPLAY 1.510638 (75 2625);
PAINT ORANGE (75 2625);
DISPLAY INVISIBLE (75 2625);
FORCEPROP 1 LASTPIN (25 2375) $PN 2
J 0
(35 2355);
DISPLAY 0.787234 (35 2355);
PAINT ORANGE (35 2355);
DISPLAY INVISIBLE (35 2355);
FORCEPROP 1 LASTPIN (25 2575) $PN 1
J 0
(35 2555);
DISPLAY 0.787234 (35 2555);
PAINT ORANGE (35 2555);
DISPLAY INVISIBLE (35 2555);
FORCEADD W_VCC_CIRCLE..1
(-275 2925);
FORCEPROP 3 LASTPIN (-275 2925) SIG_NAME P1V2_AUX_BMC\g
J 0
(-265 2935);
DISPLAY 0.659574 (-265 2935);
PAINT MONO (-265 2935);
DISPLAY INVISIBLE (-265 2935);
FORCEPROP 1 LAST HDL_POWER P1V2_AUX_BMC
J 1
(-254 3000);
DISPLAY 0.872340 (-254 3000);
PAINT ORANGE (-254 3000);
FORCEPROP 1 LAST PATH I15
J 0
(-275 2925);
DISPLAY 0.617021 (-275 2925);
PAINT GREEN (-275 2925);
DISPLAY INVISIBLE (-275 2925);
FORCEPROP 1 LAST BODY_TYPE PLUMBING
J 0
(-263 2919);
DISPLAY 0.340426 (-263 2919);
PAINT GREEN (-263 2919);
DISPLAY INVISIBLE (-263 2919);
FORCEPROP 1 LAST CDS_LMAN_SYM_OUTLINE -100,100,100,-100
J 0
(-275 2925);
DISPLAY 0.468085 (-275 2925);
PAINT GREEN (-275 2925);
DISPLAY INVISIBLE (-275 2925);
FORCEPROP 2 LAST CDS_LIB w_power
J 0
(-275 2925);
PAINT MONO (-275 2925);
DISPLAY INVISIBLE (-275 2925);
FORCEADD GND..1
(-500 3175);
FORCEPROP 3 LASTPIN (-500 3225) SIG_NAME GND\g
J 0
(-490 3235);
DISPLAY 0.659574 (-490 3235);
PAINT MONO (-490 3235);
DISPLAY INVISIBLE (-490 3235);
FORCEPROP 1 LAST PATH I16
J 0
(-425 3175);
DISPLAY 0.872340 (-425 3175);
PAINT AQUA (-425 3175);
DISPLAY INVISIBLE (-425 3175);
FORCEPROP 1 LAST VOLTAGE 0.0V
J 0
(-545 3132);
DISPLAY 0.340426 (-545 3132);
PAINT GREEN (-545 3132);
DISPLAY INVISIBLE (-545 3132);
FORCEPROP 1 LAST BODY_TYPE PLUMBING
J 0
(-545 3132);
DISPLAY 0.340426 (-545 3132);
PAINT GREEN (-545 3132);
DISPLAY INVISIBLE (-545 3132);
FORCEPROP 2 LAST CDS_LIB mstr_symbols
J 0
(-500 3175);
PAINT MONO (-500 3175);
DISPLAY INVISIBLE (-500 3175);
FORCEPROP 1 LAST SIZE 1B
J 0
(-425 3125);
DISPLAY 0.872340 (-425 3125);
PAINT AQUA (-425 3125);
DISPLAY INVISIBLE (-425 3125);
FORCEPROP 1 LAST HDL_POWER GND
J 0
(-500 3325);
DISPLAY 0.872340 (-500 3325);
PAINT GREEN (-500 3325);
DISPLAY INVISIBLE (-500 3325);
FORCEADD SC4D7U10V3KX-GP..1
(-500 3550);
FORCEPROP 1 LAST LOCATION C25W39
J 0
(-475 3580);
DISPLAY 0.617021 (-475 3580);
PAINT GREEN (-475 3580);
FORCEPROP 1 LAST VALUE SC4D7U10V3KX-GP
J 0
(-475 3500);
DISPLAY 0.617021 (-475 3500);
PAINT GREEN (-475 3500);
FORCEPROP 1 LAST PATH I17
J 0
(-500 3550);
DISPLAY 0.617021 (-500 3550);
PAINT GREEN (-500 3550);
DISPLAY INVISIBLE (-500 3550);
FORCEPROP 1 LAST CDS_LMAN_SYM_OUTLINE -50,25,50,-25
J 0
(-500 3550);
DISPLAY 0.468085 (-500 3550);
PAINT GREEN (-500 3550);
DISPLAY INVISIBLE (-500 3550);
FORCEPROP 2 LAST CDS_LIB w_hdl
J 0
(-500 3550);
PAINT MONO (-500 3550);
DISPLAY INVISIBLE (-500 3550);
FORCEPROP 1 LAST PACK_TYPE SMD-BCG
J 0
(-500 3550);
DISPLAY 0.617021 (-500 3550);
PAINT GREEN (-500 3550);
DISPLAY INVISIBLE (-500 3550);
FORCEPROP 1 LAST PART_NUMBER 78.47523.5BL
J 0
(-500 3550);
DISPLAY 0.617021 (-500 3550);
PAINT GREEN (-500 3550);
DISPLAY INVISIBLE (-500 3550);
FORCEADD SCD1U16V2KX-3GP..1
(-900 3550);
FORCEPROP 1 LAST VALUE SCD1U16V2KX-3GP
J 0
(-875 3500);
DISPLAY 0.617021 (-875 3500);
PAINT GREEN (-875 3500);
FORCEPROP 1 LAST LOCATION C25W38
J 0
(-875 3580);
DISPLAY 0.617021 (-875 3580);
PAINT GREEN (-875 3580);
FORCEPROP 1 LAST PATH I18
J 0
(-900 3550);
DISPLAY 0.617021 (-900 3550);
PAINT GREEN (-900 3550);
DISPLAY INVISIBLE (-900 3550);
FORCEPROP 2 LAST CDS_LIB w_hdl
J 0
(-900 3550);
PAINT MONO (-900 3550);
DISPLAY INVISIBLE (-900 3550);
FORCEPROP 1 LAST CDS_LMAN_SYM_OUTLINE -50,25,50,-25
J 0
(-900 3550);
DISPLAY 0.468085 (-900 3550);
PAINT GREEN (-900 3550);
DISPLAY INVISIBLE (-900 3550);
FORCEPROP 1 LAST PACK_TYPE SMD-BCG
J 0
(-900 3550);
DISPLAY 0.617021 (-900 3550);
PAINT GREEN (-900 3550);
DISPLAY INVISIBLE (-900 3550);
FORCEPROP 1 LAST PART_NUMBER 78.10421.2FL
J 0
(-900 3550);
DISPLAY 0.617021 (-900 3550);
PAINT GREEN (-900 3550);
DISPLAY INVISIBLE (-900 3550);
FORCEADD CAP..1
(-275 2475);
FORCEPROP 1 LAST TOLERANCE 10%
J 0
(-225 2375);
DISPLAY 0.617021 (-225 2375);
PAINT SKYBLUE (-225 2375);
FORCEPROP 1 LAST VOLTAGE 6.3V
J 0
(-225 2425);
DISPLAY 0.617021 (-225 2425);
PAINT SKYBLUE (-225 2425);
FORCEPROP 1 LAST VALUE 1.0UF
J 0
(-225 2500);
DISPLAY 0.617021 (-225 2500);
PAINT SKYBLUE (-225 2500);
FORCEPROP 1 LAST PART_NUMBER D97712-004
R 1
J 0
(-325 2275);
DISPLAY 0.617021 (-325 2275);
PAINT BLUE (-325 2275);
FORCEPROP 1 LAST PACK_TYPE 0402
J 0
(-225 2275);
DISPLAY 0.617021 (-225 2275);
PAINT SKYBLUE (-225 2275);
FORCEPROP 1 LAST MATERIAL X6S
J 0
(-225 2325);
DISPLAY 0.617021 (-225 2325);
PAINT SKYBLUE (-225 2325);
FORCEPROP 1 LAST LOCATION C25W51
J 0
(-225 2575);
DISPLAY 0.617021 (-225 2575);
PAINT AQUA (-225 2575);
FORCEPROP 1 LAST PATH I19
J 0
(-225 2625);
DISPLAY 0.978723 (-225 2625);
PAINT WHITE (-225 2625);
DISPLAY INVISIBLE (-225 2625);
FORCEPROP 2 LAST CDS_LIB mstr_discrete
J 0
(-275 2475);
PAINT MONO (-275 2475);
DISPLAY INVISIBLE (-275 2475);
FORCEPROP 2 LAST ROOM BMC
J 0
(-225 2625);
DISPLAY 1.510638 (-225 2625);
PAINT ORANGE (-225 2625);
DISPLAY INVISIBLE (-225 2625);
FORCEPROP 2 LAST BOM_COST SM_CONTROLLER
J 0
(-225 2625);
PAINT MONO (-225 2625);
DISPLAY INVISIBLE (-225 2625);
FORCEPROP 1 LASTPIN (-275 2375) $PN 2
J 0
(-265 2355);
DISPLAY 0.787234 (-265 2355);
PAINT ORANGE (-265 2355);
DISPLAY INVISIBLE (-265 2355);
FORCEPROP 1 LASTPIN (-275 2575) $PN 1
J 0
(-265 2555);
DISPLAY 0.787234 (-265 2555);
PAINT ORANGE (-265 2555);
DISPLAY INVISIBLE (-265 2555);
FORCEADD SC4D7U10V3KX-GP..1
(650 1450);
FORCEPROP 1 LAST VALUE SC4D7U10V3KX-GP
J 0
(675 1400);
DISPLAY 0.617021 (675 1400);
PAINT GREEN (675 1400);
FORCEPROP 1 LAST LOCATION C25W65
J 0
(675 1480);
DISPLAY 0.617021 (675 1480);
PAINT GREEN (675 1480);
FORCEPROP 1 LAST PATH I2
J 0
(650 1450);
DISPLAY 0.617021 (650 1450);
PAINT GREEN (650 1450);
DISPLAY INVISIBLE (650 1450);
FORCEPROP 1 LAST PACK_TYPE SMD-BCG
J 0
(650 1450);
DISPLAY 0.617021 (650 1450);
PAINT GREEN (650 1450);
DISPLAY INVISIBLE (650 1450);
FORCEPROP 1 LAST PART_NUMBER 78.47523.5BL
J 0
(650 1450);
DISPLAY 0.617021 (650 1450);
PAINT GREEN (650 1450);
DISPLAY INVISIBLE (650 1450);
FORCEPROP 1 LAST CDS_LMAN_SYM_OUTLINE -50,25,50,-25
J 0
(650 1450);
DISPLAY 0.468085 (650 1450);
PAINT GREEN (650 1450);
DISPLAY INVISIBLE (650 1450);
FORCEPROP 2 LAST CDS_LIB w_hdl
J 0
(650 1450);
PAINT MONO (650 1450);
DISPLAY INVISIBLE (650 1450);
FORCEADD W_VCC_CIRCLE..1
(-300 1925);
FORCEPROP 3 LASTPIN (-300 1925) SIG_NAME VCC_D_PLL_3V3\g
J 0
(-290 1935);
DISPLAY 0.659574 (-290 1935);
PAINT MONO (-290 1935);
DISPLAY INVISIBLE (-290 1935);
FORCEPROP 1 LAST HDL_POWER VCC_D_PLL_3V3
J 1
(-279 2000);
DISPLAY 0.872340 (-279 2000);
PAINT ORANGE (-279 2000);
FORCEPROP 1 LAST PATH I20
J 0
(-300 1925);
DISPLAY 0.617021 (-300 1925);
PAINT GREEN (-300 1925);
DISPLAY INVISIBLE (-300 1925);
FORCEPROP 1 LAST BODY_TYPE PLUMBING
J 0
(-288 1919);
DISPLAY 0.340426 (-288 1919);
PAINT GREEN (-288 1919);
DISPLAY INVISIBLE (-288 1919);
FORCEPROP 1 LAST CDS_LMAN_SYM_OUTLINE -100,100,100,-100
J 0
(-300 1925);
DISPLAY 0.468085 (-300 1925);
PAINT GREEN (-300 1925);
DISPLAY INVISIBLE (-300 1925);
FORCEPROP 2 LAST CDS_LIB w_power
J 0
(-300 1925);
PAINT MONO (-300 1925);
DISPLAY INVISIBLE (-300 1925);
FORCEADD SC4D7U10V3KX-GP..1
(-950 2575);
FORCEPROP 1 LAST LOCATION C25W50
J 0
(-925 2605);
DISPLAY 0.617021 (-925 2605);
PAINT GREEN (-925 2605);
FORCEPROP 1 LAST VALUE SC4D7U10V3KX-GP
J 0
(-925 2525);
DISPLAY 0.617021 (-925 2525);
PAINT GREEN (-925 2525);
FORCEPROP 1 LAST PATH I21
J 0
(-950 2575);
DISPLAY 0.617021 (-950 2575);
PAINT GREEN (-950 2575);
DISPLAY INVISIBLE (-950 2575);
FORCEPROP 1 LAST PART_NUMBER 78.47523.5BL
J 0
(-950 2575);
DISPLAY 0.617021 (-950 2575);
PAINT GREEN (-950 2575);
DISPLAY INVISIBLE (-950 2575);
FORCEPROP 1 LAST PACK_TYPE SMD-BCG
J 0
(-950 2575);
DISPLAY 0.617021 (-950 2575);
PAINT GREEN (-950 2575);
DISPLAY INVISIBLE (-950 2575);
FORCEPROP 1 LAST CDS_LMAN_SYM_OUTLINE -50,25,50,-25
J 0
(-950 2575);
DISPLAY 0.468085 (-950 2575);
PAINT GREEN (-950 2575);
DISPLAY INVISIBLE (-950 2575);
FORCEPROP 2 LAST CDS_LIB w_hdl
J 0
(-950 2575);
PAINT MONO (-950 2575);
DISPLAY INVISIBLE (-950 2575);
FORCEADD GND..1
(-950 2200);
FORCEPROP 3 LASTPIN (-950 2250) SIG_NAME GND\g
J 0
(-940 2260);
DISPLAY 0.659574 (-940 2260);
PAINT MONO (-940 2260);
DISPLAY INVISIBLE (-940 2260);
FORCEPROP 1 LAST PATH I22
J 0
(-875 2200);
DISPLAY 0.872340 (-875 2200);
PAINT AQUA (-875 2200);
DISPLAY INVISIBLE (-875 2200);
FORCEPROP 1 LAST VOLTAGE 0.0V
J 0
(-995 2157);
DISPLAY 0.340426 (-995 2157);
PAINT GREEN (-995 2157);
DISPLAY INVISIBLE (-995 2157);
FORCEPROP 1 LAST BODY_TYPE PLUMBING
J 0
(-995 2157);
DISPLAY 0.340426 (-995 2157);
PAINT GREEN (-995 2157);
DISPLAY INVISIBLE (-995 2157);
FORCEPROP 1 LAST HDL_POWER GND
J 0
(-950 2350);
DISPLAY 0.872340 (-950 2350);
PAINT GREEN (-950 2350);
DISPLAY INVISIBLE (-950 2350);
FORCEPROP 1 LAST SIZE 1B
J 0
(-875 2150);
DISPLAY 0.872340 (-875 2150);
PAINT AQUA (-875 2150);
DISPLAY INVISIBLE (-875 2150);
FORCEPROP 2 LAST CDS_LIB mstr_symbols
J 0
(-950 2200);
PAINT MONO (-950 2200);
DISPLAY INVISIBLE (-950 2200);
FORCEADD GND..1
(650 975);
FORCEPROP 3 LASTPIN (650 1025) SIG_NAME GND\g
J 0
(660 1035);
DISPLAY 0.659574 (660 1035);
PAINT MONO (660 1035);
DISPLAY INVISIBLE (660 1035);
FORCEPROP 1 LAST PATH I23
J 0
(725 975);
DISPLAY 0.872340 (725 975);
PAINT AQUA (725 975);
DISPLAY INVISIBLE (725 975);
FORCEPROP 1 LAST VOLTAGE 0.0V
J 0
(605 932);
DISPLAY 0.340426 (605 932);
PAINT GREEN (605 932);
DISPLAY INVISIBLE (605 932);
FORCEPROP 1 LAST BODY_TYPE PLUMBING
J 0
(605 932);
DISPLAY 0.340426 (605 932);
PAINT GREEN (605 932);
DISPLAY INVISIBLE (605 932);
FORCEPROP 1 LAST HDL_POWER GND
J 0
(650 1125);
DISPLAY 0.872340 (650 1125);
PAINT GREEN (650 1125);
DISPLAY INVISIBLE (650 1125);
FORCEPROP 1 LAST SIZE 1B
J 0
(725 925);
DISPLAY 0.872340 (725 925);
PAINT AQUA (725 925);
DISPLAY INVISIBLE (725 925);
FORCEPROP 2 LAST CDS_LIB mstr_symbols
J 0
(650 975);
PAINT MONO (650 975);
DISPLAY INVISIBLE (650 975);
FORCEADD SCD1U16V2KX-3GP..1
(250 1450);
FORCEPROP 1 LAST LOCATION C25W64
J 0
(275 1480);
DISPLAY 0.617021 (275 1480);
PAINT GREEN (275 1480);
FORCEPROP 1 LAST VALUE SCD1U16V2KX-3GP
J 0
(275 1400);
DISPLAY 0.617021 (275 1400);
PAINT GREEN (275 1400);
FORCEPROP 1 LAST PATH I24
J 0
(250 1450);
DISPLAY 0.617021 (250 1450);
PAINT GREEN (250 1450);
DISPLAY INVISIBLE (250 1450);
FORCEPROP 1 LAST PART_NUMBER 78.10421.2FL
J 0
(250 1450);
DISPLAY 0.617021 (250 1450);
PAINT GREEN (250 1450);
DISPLAY INVISIBLE (250 1450);
FORCEPROP 1 LAST PACK_TYPE SMD-BCG
J 0
(250 1450);
DISPLAY 0.617021 (250 1450);
PAINT GREEN (250 1450);
DISPLAY INVISIBLE (250 1450);
FORCEPROP 1 LAST CDS_LMAN_SYM_OUTLINE -50,25,50,-25
J 0
(250 1450);
DISPLAY 0.468085 (250 1450);
PAINT GREEN (250 1450);
DISPLAY INVISIBLE (250 1450);
FORCEPROP 2 LAST CDS_LIB w_hdl
J 0
(250 1450);
PAINT MONO (250 1450);
DISPLAY INVISIBLE (250 1450);
FORCEADD CAP..1
(-300 1425);
FORCEPROP 1 LAST VOLTAGE 6.3V
J 0
(-250 1375);
DISPLAY 0.617021 (-250 1375);
PAINT SKYBLUE (-250 1375);
FORCEPROP 1 LAST TOLERANCE 10%
J 0
(-250 1325);
DISPLAY 0.617021 (-250 1325);
PAINT SKYBLUE (-250 1325);
FORCEPROP 1 LAST PART_NUMBER D97712-004
R 1
J 0
(-350 1225);
DISPLAY 0.617021 (-350 1225);
PAINT BLUE (-350 1225);
FORCEPROP 1 LAST VALUE 1.0UF
J 0
(-250 1450);
DISPLAY 0.617021 (-250 1450);
PAINT SKYBLUE (-250 1450);
FORCEPROP 1 LAST LOCATION C25W63
J 0
(-250 1525);
DISPLAY 0.617021 (-250 1525);
PAINT AQUA (-250 1525);
FORCEPROP 1 LAST PACK_TYPE 0402
J 0
(-250 1225);
DISPLAY 0.617021 (-250 1225);
PAINT SKYBLUE (-250 1225);
FORCEPROP 1 LAST MATERIAL X6S
J 0
(-250 1275);
DISPLAY 0.617021 (-250 1275);
PAINT SKYBLUE (-250 1275);
FORCEPROP 1 LAST PATH I25
J 0
(-250 1575);
DISPLAY 0.978723 (-250 1575);
PAINT WHITE (-250 1575);
DISPLAY INVISIBLE (-250 1575);
FORCEPROP 2 LAST ROOM BMC
J 0
(-250 1575);
DISPLAY 1.510638 (-250 1575);
PAINT ORANGE (-250 1575);
DISPLAY INVISIBLE (-250 1575);
FORCEPROP 2 LAST BOM_COST SM_CONTROLLER
J 0
(-250 1575);
PAINT MONO (-250 1575);
DISPLAY INVISIBLE (-250 1575);
FORCEPROP 2 LAST CDS_LIB mstr_discrete
J 0
(-300 1425);
PAINT MONO (-300 1425);
DISPLAY INVISIBLE (-300 1425);
FORCEPROP 1 LASTPIN (-300 1325) $PN 2
J 0
(-290 1305);
DISPLAY 0.787234 (-290 1305);
PAINT ORANGE (-290 1305);
DISPLAY INVISIBLE (-290 1305);
FORCEPROP 1 LASTPIN (-300 1525) $PN 1
J 0
(-290 1505);
DISPLAY 0.787234 (-290 1505);
PAINT ORANGE (-290 1505);
DISPLAY INVISIBLE (-290 1505);
FORCEADD HCB1608KF-800T30-GP..1
R 1
(-850 1775);
FORCEPROP 1 LAST LOCATION FB2T6
J 0
(-925 1825);
DISPLAY 0.617021 (-925 1825);
PAINT GREEN (-925 1825);
FORCEPROP 1 LAST VALUE HCB1608KF-800T30-GP
J 0
(-950 1700);
DISPLAY 0.617021 (-950 1700);
PAINT GREEN (-950 1700);
FORCEPROP 1 LAST PATH I26
R 1
J 0
(-850 1775);
DISPLAY 0.617021 (-850 1775);
PAINT GREEN (-850 1775);
DISPLAY INVISIBLE (-850 1775);
FORCEPROP 2 LAST CDS_LIB w_hdl
J 0
(-850 1775);
PAINT MONO (-850 1775);
DISPLAY INVISIBLE (-850 1775);
FORCEPROP 1 LAST CDS_LMAN_SYM_OUTLINE -50,100,50,-100
R 1
J 0
(-850 1775);
DISPLAY 0.468085 (-850 1775);
PAINT GREEN (-850 1775);
DISPLAY INVISIBLE (-850 1775);
FORCEPROP 1 LAST PART_NUMBER 68.00230.231
R 1
J 0
(-850 1775);
DISPLAY 0.617021 (-850 1775);
PAINT GREEN (-850 1775);
DISPLAY INVISIBLE (-850 1775);
FORCEPROP 1 LAST PACK_TYPE DISCRET-G9
R 1
J 0
(-850 1775);
DISPLAY 0.617021 (-850 1775);
PAINT GREEN (-850 1775);
DISPLAY INVISIBLE (-850 1775);
FORCEADD W_VCC_CIRCLE..1
(-1125 5225);
FORCEPROP 3 LASTPIN (-1125 5225) SIG_NAME VCC_VA_3V3\g
J 0
(-1115 5235);
DISPLAY 0.659574 (-1115 5235);
PAINT MONO (-1115 5235);
DISPLAY INVISIBLE (-1115 5235);
FORCEPROP 1 LAST HDL_POWER VCC_VA_3V3
J 1
(-1104 5300);
DISPLAY 0.872340 (-1104 5300);
PAINT ORANGE (-1104 5300);
FORCEPROP 1 LAST PATH I27
J 0
(-1125 5225);
DISPLAY 0.617021 (-1125 5225);
PAINT GREEN (-1125 5225);
DISPLAY INVISIBLE (-1125 5225);
FORCEPROP 1 LAST BODY_TYPE PLUMBING
J 0
(-1113 5219);
DISPLAY 0.340426 (-1113 5219);
PAINT GREEN (-1113 5219);
DISPLAY INVISIBLE (-1113 5219);
FORCEPROP 2 LAST CDS_LIB w_power
J 0
(-1125 5225);
PAINT MONO (-1125 5225);
DISPLAY INVISIBLE (-1125 5225);
FORCEPROP 1 LAST CDS_LMAN_SYM_OUTLINE -100,100,100,-100
J 0
(-1125 5225);
DISPLAY 0.468085 (-1125 5225);
PAINT GREEN (-1125 5225);
DISPLAY INVISIBLE (-1125 5225);
FORCEADD SC4D7U10V3KX-GP..1
(-1125 4750);
FORCEPROP 1 LAST VALUE SC4D7U10V3KX-GP
J 0
(-1100 4700);
DISPLAY 0.617021 (-1100 4700);
PAINT GREEN (-1100 4700);
FORCEPROP 1 LAST LOCATION C25W69
J 0
(-1100 4780);
DISPLAY 0.617021 (-1100 4780);
PAINT GREEN (-1100 4780);
FORCEPROP 1 LAST PATH I28
J 0
(-1125 4750);
DISPLAY 0.617021 (-1125 4750);
PAINT GREEN (-1125 4750);
DISPLAY INVISIBLE (-1125 4750);
FORCEPROP 1 LAST PACK_TYPE SMD-BCG
J 0
(-1125 4750);
DISPLAY 0.617021 (-1125 4750);
PAINT GREEN (-1125 4750);
DISPLAY INVISIBLE (-1125 4750);
FORCEPROP 1 LAST PART_NUMBER 78.47523.5BL
J 0
(-1125 4750);
DISPLAY 0.617021 (-1125 4750);
PAINT GREEN (-1125 4750);
DISPLAY INVISIBLE (-1125 4750);
FORCEPROP 2 LAST CDS_LIB w_hdl
J 0
(-1125 4750);
PAINT MONO (-1125 4750);
DISPLAY INVISIBLE (-1125 4750);
FORCEPROP 1 LAST CDS_LMAN_SYM_OUTLINE -50,25,50,-25
J 0
(-1125 4750);
DISPLAY 0.468085 (-1125 4750);
PAINT GREEN (-1125 4750);
DISPLAY INVISIBLE (-1125 4750);
FORCEADD GND..1
(-1125 4275);
FORCEPROP 3 LASTPIN (-1125 4325) SIG_NAME GND\g
J 0
(-1115 4335);
DISPLAY 0.659574 (-1115 4335);
PAINT MONO (-1115 4335);
DISPLAY INVISIBLE (-1115 4335);
FORCEPROP 1 LAST PATH I29
J 0
(-1050 4275);
DISPLAY 0.872340 (-1050 4275);
PAINT AQUA (-1050 4275);
DISPLAY INVISIBLE (-1050 4275);
FORCEPROP 1 LAST HDL_POWER GND
J 0
(-1125 4425);
DISPLAY 0.872340 (-1125 4425);
PAINT GREEN (-1125 4425);
DISPLAY INVISIBLE (-1125 4425);
FORCEPROP 1 LAST SIZE 1B
J 0
(-1050 4225);
DISPLAY 0.872340 (-1050 4225);
PAINT AQUA (-1050 4225);
DISPLAY INVISIBLE (-1050 4225);
FORCEPROP 2 LAST CDS_LIB mstr_symbols
J 0
(-1125 4275);
PAINT MONO (-1125 4275);
DISPLAY INVISIBLE (-1125 4275);
FORCEPROP 1 LAST BODY_TYPE PLUMBING
J 0
(-1170 4232);
DISPLAY 0.340426 (-1170 4232);
PAINT GREEN (-1170 4232);
DISPLAY INVISIBLE (-1170 4232);
FORCEPROP 1 LAST VOLTAGE 0.0V
J 0
(-1170 4232);
DISPLAY 0.340426 (-1170 4232);
PAINT GREEN (-1170 4232);
DISPLAY INVISIBLE (-1170 4232);
FORCEADD W_VCC_CIRCLE..1
(575 5175);
FORCEPROP 3 LASTPIN (575 5175) SIG_NAME P3V3_USB2A_ALG\g
J 0
(585 5185);
DISPLAY 0.659574 (585 5185);
PAINT MONO (585 5185);
DISPLAY INVISIBLE (585 5185);
FORCEPROP 1 LAST HDL_POWER P3V3_USB2A_ALG
J 1
(596 5250);
DISPLAY 0.872340 (596 5250);
PAINT ORANGE (596 5250);
FORCEPROP 1 LAST PATH I3
J 0
(575 5175);
DISPLAY 0.617021 (575 5175);
PAINT GREEN (575 5175);
DISPLAY INVISIBLE (575 5175);
FORCEPROP 1 LAST BODY_TYPE PLUMBING
J 0
(587 5169);
DISPLAY 0.340426 (587 5169);
PAINT GREEN (587 5169);
DISPLAY INVISIBLE (587 5169);
FORCEPROP 1 LAST CDS_LMAN_SYM_OUTLINE -100,100,100,-100
J 0
(575 5175);
DISPLAY 0.468085 (575 5175);
PAINT GREEN (575 5175);
DISPLAY INVISIBLE (575 5175);
FORCEPROP 2 LAST CDS_LIB w_power
J 0
(575 5175);
PAINT MONO (575 5175);
DISPLAY INVISIBLE (575 5175);
FORCEADD SCD1U16V2KX-3GP..1
(-1525 4750);
FORCEPROP 1 LAST LOCATION C25W68
J 0
(-1500 4780);
DISPLAY 0.617021 (-1500 4780);
PAINT GREEN (-1500 4780);
FORCEPROP 1 LAST VALUE SCD1U16V2KX-3GP
J 0
(-1500 4700);
DISPLAY 0.617021 (-1500 4700);
PAINT GREEN (-1500 4700);
FORCEPROP 1 LAST PATH I30
J 0
(-1525 4750);
DISPLAY 0.617021 (-1525 4750);
PAINT GREEN (-1525 4750);
DISPLAY INVISIBLE (-1525 4750);
FORCEPROP 1 LAST PART_NUMBER 78.10421.2FL
J 0
(-1525 4750);
DISPLAY 0.617021 (-1525 4750);
PAINT GREEN (-1525 4750);
DISPLAY INVISIBLE (-1525 4750);
FORCEPROP 1 LAST PACK_TYPE SMD-BCG
J 0
(-1525 4750);
DISPLAY 0.617021 (-1525 4750);
PAINT GREEN (-1525 4750);
DISPLAY INVISIBLE (-1525 4750);
FORCEPROP 2 LAST CDS_LIB w_hdl
J 0
(-1525 4750);
PAINT MONO (-1525 4750);
DISPLAY INVISIBLE (-1525 4750);
FORCEPROP 1 LAST CDS_LMAN_SYM_OUTLINE -50,25,50,-25
J 0
(-1525 4750);
DISPLAY 0.468085 (-1525 4750);
PAINT GREEN (-1525 4750);
DISPLAY INVISIBLE (-1525 4750);
FORCEADD CAP..1
(-1825 4725);
FORCEPROP 1 LAST LOCATION C25W67
J 0
(-1775 4825);
DISPLAY 0.617021 (-1775 4825);
PAINT AQUA (-1775 4825);
FORCEPROP 1 LAST VALUE 1.0UF
J 0
(-1775 4750);
DISPLAY 0.617021 (-1775 4750);
PAINT SKYBLUE (-1775 4750);
FORCEPROP 1 LAST VOLTAGE 6.3V
J 0
(-1775 4675);
DISPLAY 0.617021 (-1775 4675);
PAINT SKYBLUE (-1775 4675);
FORCEPROP 1 LAST TOLERANCE 10%
J 0
(-1775 4625);
DISPLAY 0.617021 (-1775 4625);
PAINT SKYBLUE (-1775 4625);
FORCEPROP 1 LAST MATERIAL X6S
J 0
(-1775 4575);
DISPLAY 0.617021 (-1775 4575);
PAINT SKYBLUE (-1775 4575);
FORCEPROP 1 LAST PART_NUMBER D97712-004
R 1
J 0
(-1875 4525);
DISPLAY 0.617021 (-1875 4525);
PAINT BLUE (-1875 4525);
FORCEPROP 1 LAST PACK_TYPE 0402
J 0
(-1775 4525);
DISPLAY 0.617021 (-1775 4525);
PAINT SKYBLUE (-1775 4525);
FORCEPROP 1 LAST PATH I31
J 0
(-1775 4875);
DISPLAY 0.978723 (-1775 4875);
PAINT WHITE (-1775 4875);
DISPLAY INVISIBLE (-1775 4875);
FORCEPROP 2 LAST ROOM BMC
J 0
(-1775 4875);
DISPLAY 1.510638 (-1775 4875);
PAINT ORANGE (-1775 4875);
DISPLAY INVISIBLE (-1775 4875);
FORCEPROP 2 LAST BOM_COST SM_CONTROLLER
J 0
(-1775 4875);
PAINT MONO (-1775 4875);
DISPLAY INVISIBLE (-1775 4875);
FORCEPROP 2 LAST CDS_LIB mstr_discrete
J 0
(-1825 4725);
PAINT MONO (-1825 4725);
DISPLAY INVISIBLE (-1825 4725);
FORCEPROP 1 LASTPIN (-1825 4625) $PN 2
J 0
(-1815 4605);
DISPLAY 0.787234 (-1815 4605);
PAINT ORANGE (-1815 4605);
DISPLAY INVISIBLE (-1815 4605);
FORCEPROP 1 LASTPIN (-1825 4825) $PN 1
J 0
(-1815 4805);
DISPLAY 0.787234 (-1815 4805);
PAINT ORANGE (-1815 4805);
DISPLAY INVISIBLE (-1815 4805);
FORCEADD HCB1608KF-800T30-GP..1
R 1
(-2725 5075);
FORCEPROP 1 LAST VALUE HCB1608KF-800T30-GP
J 0
(-2825 5000);
DISPLAY 0.617021 (-2825 5000);
PAINT GREEN (-2825 5000);
FORCEPROP 1 LAST LOCATION FB2T1
J 0
(-2800 5125);
DISPLAY 0.617021 (-2800 5125);
PAINT GREEN (-2800 5125);
FORCEPROP 1 LAST PATH I32
R 1
J 0
(-2725 5075);
DISPLAY 0.617021 (-2725 5075);
PAINT GREEN (-2725 5075);
DISPLAY INVISIBLE (-2725 5075);
FORCEPROP 1 LAST PACK_TYPE DISCRET-G9
R 1
J 0
(-2725 5075);
DISPLAY 0.617021 (-2725 5075);
PAINT GREEN (-2725 5075);
DISPLAY INVISIBLE (-2725 5075);
FORCEPROP 1 LAST PART_NUMBER 68.00230.231
R 1
J 0
(-2725 5075);
DISPLAY 0.617021 (-2725 5075);
PAINT GREEN (-2725 5075);
DISPLAY INVISIBLE (-2725 5075);
FORCEPROP 1 LAST CDS_LMAN_SYM_OUTLINE -50,100,50,-100
R 1
J 0
(-2725 5075);
DISPLAY 0.468085 (-2725 5075);
PAINT GREEN (-2725 5075);
DISPLAY INVISIBLE (-2725 5075);
FORCEPROP 2 LAST CDS_LIB w_hdl
J 0
(-2725 5075);
PAINT MONO (-2725 5075);
DISPLAY INVISIBLE (-2725 5075);
FORCEADD CAP..1
(-2075 4725);
FORCEPROP 1 LAST LOCATION C25W66
J 0
(-2025 4825);
DISPLAY 0.617021 (-2025 4825);
PAINT AQUA (-2025 4825);
FORCEPROP 1 LAST VOLTAGE 6.3V
J 0
(-2025 4675);
DISPLAY 0.617021 (-2025 4675);
PAINT SKYBLUE (-2025 4675);
FORCEPROP 1 LAST TOLERANCE 10%
J 0
(-2025 4625);
DISPLAY 0.617021 (-2025 4625);
PAINT SKYBLUE (-2025 4625);
FORCEPROP 1 LAST VALUE 1.0UF
J 0
(-2025 4750);
DISPLAY 0.617021 (-2025 4750);
PAINT SKYBLUE (-2025 4750);
FORCEPROP 1 LAST MATERIAL X6S
J 0
(-2025 4575);
DISPLAY 0.617021 (-2025 4575);
PAINT SKYBLUE (-2025 4575);
FORCEPROP 1 LAST PACK_TYPE 0402
J 0
(-2025 4525);
DISPLAY 0.617021 (-2025 4525);
PAINT SKYBLUE (-2025 4525);
FORCEPROP 1 LAST PART_NUMBER D97712-004
R 1
J 0
(-2125 4525);
DISPLAY 0.617021 (-2125 4525);
PAINT BLUE (-2125 4525);
FORCEPROP 1 LAST PATH I33
J 0
(-2025 4875);
DISPLAY 0.978723 (-2025 4875);
PAINT WHITE (-2025 4875);
DISPLAY INVISIBLE (-2025 4875);
FORCEPROP 2 LAST ROOM BMC
J 0
(-2025 4875);
DISPLAY 1.510638 (-2025 4875);
PAINT ORANGE (-2025 4875);
DISPLAY INVISIBLE (-2025 4875);
FORCEPROP 2 LAST BOM_COST SM_CONTROLLER
J 0
(-2025 4875);
PAINT MONO (-2025 4875);
DISPLAY INVISIBLE (-2025 4875);
FORCEPROP 2 LAST CDS_LIB mstr_discrete
J 0
(-2075 4725);
PAINT MONO (-2075 4725);
DISPLAY INVISIBLE (-2075 4725);
FORCEPROP 1 LASTPIN (-2075 4625) $PN 2
J 0
(-2065 4605);
DISPLAY 0.787234 (-2065 4605);
PAINT ORANGE (-2065 4605);
DISPLAY INVISIBLE (-2065 4605);
FORCEPROP 1 LASTPIN (-2075 4825) $PN 1
J 0
(-2065 4805);
DISPLAY 0.787234 (-2065 4805);
PAINT ORANGE (-2065 4805);
DISPLAY INVISIBLE (-2065 4805);
FORCEADD W_VCC_CIRCLE..1
(-2200 3975);
FORCEPROP 3 LASTPIN (-2200 3975) SIG_NAME P1V15_AUX_BMC\g
J 0
(-2190 3985);
DISPLAY 0.659574 (-2190 3985);
PAINT MONO (-2190 3985);
DISPLAY INVISIBLE (-2190 3985);
FORCEPROP 1 LAST HDL_POWER P1V15_AUX_BMC
J 1
(-2179 4050);
DISPLAY 0.872340 (-2179 4050);
PAINT ORANGE (-2179 4050);
FORCEPROP 1 LAST PATH I34
J 0
(-2200 3975);
DISPLAY 0.617021 (-2200 3975);
PAINT GREEN (-2200 3975);
DISPLAY INVISIBLE (-2200 3975);
FORCEPROP 2 LAST CDS_LIB w_power
J 0
(-2200 3975);
PAINT MONO (-2200 3975);
DISPLAY INVISIBLE (-2200 3975);
FORCEPROP 1 LAST CDS_LMAN_SYM_OUTLINE -100,100,100,-100
J 0
(-2200 3975);
DISPLAY 0.468085 (-2200 3975);
PAINT GREEN (-2200 3975);
DISPLAY INVISIBLE (-2200 3975);
FORCEPROP 1 LAST BODY_TYPE PLUMBING
J 0
(-2188 3969);
DISPLAY 0.340426 (-2188 3969);
PAINT GREEN (-2188 3969);
DISPLAY INVISIBLE (-2188 3969);
FORCEADD CAP..1
(-1450 3525);
FORCEPROP 1 LAST VOLTAGE 6.3V
J 0
(-1400 3475);
DISPLAY 0.617021 (-1400 3475);
PAINT SKYBLUE (-1400 3475);
FORCEPROP 1 LAST TOLERANCE 10%
J 0
(-1400 3425);
DISPLAY 0.617021 (-1400 3425);
PAINT SKYBLUE (-1400 3425);
FORCEPROP 1 LAST MATERIAL X6S
J 0
(-1400 3375);
DISPLAY 0.617021 (-1400 3375);
PAINT SKYBLUE (-1400 3375);
FORCEPROP 1 LAST PACK_TYPE 0402
J 0
(-1400 3325);
DISPLAY 0.617021 (-1400 3325);
PAINT SKYBLUE (-1400 3325);
FORCEPROP 1 LAST PART_NUMBER D97712-004
R 1
J 0
(-1500 3325);
DISPLAY 0.617021 (-1500 3325);
PAINT BLUE (-1500 3325);
FORCEPROP 1 LAST VALUE 1.0UF
J 0
(-1400 3550);
DISPLAY 0.617021 (-1400 3550);
PAINT SKYBLUE (-1400 3550);
FORCEPROP 1 LAST LOCATION C25W37
J 0
(-1400 3625);
DISPLAY 0.617021 (-1400 3625);
PAINT AQUA (-1400 3625);
FORCEPROP 1 LAST PATH I35
J 0
(-1400 3675);
DISPLAY 0.978723 (-1400 3675);
PAINT WHITE (-1400 3675);
DISPLAY INVISIBLE (-1400 3675);
FORCEPROP 2 LAST CDS_LIB mstr_discrete
J 0
(-1450 3525);
PAINT MONO (-1450 3525);
DISPLAY INVISIBLE (-1450 3525);
FORCEPROP 2 LAST BOM_COST SM_CONTROLLER
J 0
(-1400 3675);
PAINT MONO (-1400 3675);
DISPLAY INVISIBLE (-1400 3675);
FORCEPROP 2 LAST ROOM BMC
J 0
(-1400 3675);
DISPLAY 1.510638 (-1400 3675);
PAINT ORANGE (-1400 3675);
DISPLAY INVISIBLE (-1400 3675);
FORCEPROP 1 LASTPIN (-1450 3425) $PN 2
J 0
(-1440 3405);
DISPLAY 0.787234 (-1440 3405);
PAINT ORANGE (-1440 3405);
DISPLAY INVISIBLE (-1440 3405);
FORCEPROP 1 LASTPIN (-1450 3625) $PN 1
J 0
(-1440 3605);
DISPLAY 0.787234 (-1440 3605);
PAINT ORANGE (-1440 3605);
DISPLAY INVISIBLE (-1440 3605);
FORCEADD SCD1U16V2KX-3GP..1
(-1350 2575);
FORCEPROP 1 LAST VALUE SCD1U16V2KX-3GP
J 0
(-1325 2525);
DISPLAY 0.617021 (-1325 2525);
PAINT GREEN (-1325 2525);
FORCEPROP 1 LAST LOCATION C25W49
J 0
(-1325 2605);
DISPLAY 0.617021 (-1325 2605);
PAINT GREEN (-1325 2605);
FORCEPROP 1 LAST PATH I36
J 0
(-1350 2575);
DISPLAY 0.617021 (-1350 2575);
PAINT GREEN (-1350 2575);
DISPLAY INVISIBLE (-1350 2575);
FORCEPROP 1 LAST PART_NUMBER 78.10421.2FL
J 0
(-1350 2575);
DISPLAY 0.617021 (-1350 2575);
PAINT GREEN (-1350 2575);
DISPLAY INVISIBLE (-1350 2575);
FORCEPROP 1 LAST PACK_TYPE SMD-BCG
J 0
(-1350 2575);
DISPLAY 0.617021 (-1350 2575);
PAINT GREEN (-1350 2575);
DISPLAY INVISIBLE (-1350 2575);
FORCEPROP 1 LAST CDS_LMAN_SYM_OUTLINE -50,25,50,-25
J 0
(-1350 2575);
DISPLAY 0.468085 (-1350 2575);
PAINT GREEN (-1350 2575);
DISPLAY INVISIBLE (-1350 2575);
FORCEPROP 2 LAST CDS_LIB w_hdl
J 0
(-1350 2575);
PAINT MONO (-1350 2575);
DISPLAY INVISIBLE (-1350 2575);
FORCEADD P3V3_STBY..1
(-1100 1950);
FORCEPROP 3 LASTPIN (-1100 1900) SIG_NAME P3V3_STBY\g
J 0
(-1090 1910);
DISPLAY 0.659574 (-1090 1910);
PAINT MONO (-1090 1910);
DISPLAY INVISIBLE (-1090 1910);
FORCEPROP 1 LAST PATH I37
J 0
(-1055 1952);
DISPLAY 0.340426 (-1055 1952);
PAINT GREEN (-1055 1952);
DISPLAY INVISIBLE (-1055 1952);
FORCEPROP 1 LAST VOLTAGE 3.3V
J 0
(-1145 1907);
DISPLAY 0.340426 (-1145 1907);
PAINT GREEN (-1145 1907);
DISPLAY INVISIBLE (-1145 1907);
FORCEPROP 1 LAST SIZE 1B
J 0
(-1055 1972);
DISPLAY 0.340426 (-1055 1972);
PAINT GREEN (-1055 1972);
DISPLAY INVISIBLE (-1055 1972);
FORCEPROP 1 LAST BODY_TYPE PLUMBING
J 0
(-1145 1907);
DISPLAY 0.340426 (-1145 1907);
PAINT GREEN (-1145 1907);
DISPLAY INVISIBLE (-1145 1907);
FORCEPROP 1 LAST HDL_POWER P3V3_STBY
J 0
(-1400 1825);
DISPLAY 0.872340 (-1400 1825);
PAINT ORANGE (-1400 1825);
DISPLAY INVISIBLE (-1400 1825);
FORCEPROP 2 LAST CDS_LIB mstr_symbols
J 0
(-1100 1950);
PAINT MONO (-1100 1950);
DISPLAY INVISIBLE (-1100 1950);
FORCEADD CAP..1
(-1900 2550);
FORCEPROP 1 LAST PART_NUMBER D97712-004
R 1
J 0
(-1950 2350);
DISPLAY 0.617021 (-1950 2350);
PAINT BLUE (-1950 2350);
FORCEPROP 1 LAST VOLTAGE 6.3V
J 0
(-1850 2500);
DISPLAY 0.617021 (-1850 2500);
PAINT SKYBLUE (-1850 2500);
FORCEPROP 1 LAST VALUE 1.0UF
J 0
(-1850 2575);
DISPLAY 0.617021 (-1850 2575);
PAINT SKYBLUE (-1850 2575);
FORCEPROP 1 LAST MATERIAL X6S
J 0
(-1850 2400);
DISPLAY 0.617021 (-1850 2400);
PAINT SKYBLUE (-1850 2400);
FORCEPROP 1 LAST LOCATION C25W48
J 0
(-1850 2650);
DISPLAY 0.617021 (-1850 2650);
PAINT AQUA (-1850 2650);
FORCEPROP 1 LAST TOLERANCE 10%
J 0
(-1850 2450);
DISPLAY 0.617021 (-1850 2450);
PAINT SKYBLUE (-1850 2450);
FORCEPROP 1 LAST PACK_TYPE 0402
J 0
(-1850 2350);
DISPLAY 0.617021 (-1850 2350);
PAINT SKYBLUE (-1850 2350);
FORCEPROP 1 LAST PATH I38
J 0
(-1850 2700);
DISPLAY 0.978723 (-1850 2700);
PAINT WHITE (-1850 2700);
DISPLAY INVISIBLE (-1850 2700);
FORCEPROP 2 LAST ROOM BMC
J 0
(-1850 2700);
DISPLAY 1.510638 (-1850 2700);
PAINT ORANGE (-1850 2700);
DISPLAY INVISIBLE (-1850 2700);
FORCEPROP 2 LAST BOM_COST SM_CONTROLLER
J 0
(-1850 2700);
PAINT MONO (-1850 2700);
DISPLAY INVISIBLE (-1850 2700);
FORCEPROP 2 LAST CDS_LIB mstr_discrete
J 0
(-1900 2550);
PAINT MONO (-1900 2550);
DISPLAY INVISIBLE (-1900 2550);
FORCEPROP 1 LASTPIN (-1900 2450) $PN 2
J 0
(-1890 2430);
DISPLAY 0.787234 (-1890 2430);
PAINT ORANGE (-1890 2430);
DISPLAY INVISIBLE (-1890 2430);
FORCEPROP 1 LASTPIN (-1900 2650) $PN 1
J 0
(-1890 2630);
DISPLAY 0.787234 (-1890 2630);
PAINT ORANGE (-1890 2630);
DISPLAY INVISIBLE (-1890 2630);
FORCEADD HCB1608KF-800T30-GP..1
R 1
(-1900 3875);
FORCEPROP 1 LAST LOCATION FB2T7
J 0
(-1975 3925);
DISPLAY 0.617021 (-1975 3925);
PAINT GREEN (-1975 3925);
FORCEPROP 1 LAST VALUE HCB1608KF-800T30-GP
J 0
(-2000 3800);
DISPLAY 0.617021 (-2000 3800);
PAINT GREEN (-2000 3800);
FORCEPROP 1 LAST PATH I39
R 1
J 0
(-1900 3875);
DISPLAY 0.617021 (-1900 3875);
PAINT GREEN (-1900 3875);
DISPLAY INVISIBLE (-1900 3875);
FORCEPROP 1 LAST PART_NUMBER 68.00230.231
R 1
J 0
(-1900 3875);
DISPLAY 0.617021 (-1900 3875);
PAINT GREEN (-1900 3875);
DISPLAY INVISIBLE (-1900 3875);
FORCEPROP 1 LAST PACK_TYPE DISCRET-G9
R 1
J 0
(-1900 3875);
DISPLAY 0.617021 (-1900 3875);
PAINT GREEN (-1900 3875);
DISPLAY INVISIBLE (-1900 3875);
FORCEPROP 1 LAST CDS_LMAN_SYM_OUTLINE -50,100,50,-100
R 1
J 0
(-1900 3875);
DISPLAY 0.468085 (-1900 3875);
PAINT GREEN (-1900 3875);
DISPLAY INVISIBLE (-1900 3875);
FORCEPROP 2 LAST CDS_LIB w_hdl
J 0
(-1900 3875);
PAINT MONO (-1900 3875);
DISPLAY INVISIBLE (-1900 3875);
FORCEADD CAP..1
(575 4900);
FORCEPROP 1 LAST MATERIAL X6S
J 0
(625 4750);
DISPLAY 0.617021 (625 4750);
PAINT SKYBLUE (625 4750);
FORCEPROP 1 LAST TOLERANCE 10%
J 0
(625 4800);
DISPLAY 0.617021 (625 4800);
PAINT SKYBLUE (625 4800);
FORCEPROP 1 LAST VOLTAGE 6.3V
J 0
(625 4850);
DISPLAY 0.617021 (625 4850);
PAINT SKYBLUE (625 4850);
FORCEPROP 1 LAST VALUE 1.0UF
J 0
(625 4925);
DISPLAY 0.617021 (625 4925);
PAINT SKYBLUE (625 4925);
FORCEPROP 1 LAST LOCATION C25W71
J 0
(625 5000);
DISPLAY 0.617021 (625 5000);
PAINT AQUA (625 5000);
FORCEPROP 1 LAST PACK_TYPE 0402
J 0
(625 4700);
DISPLAY 0.617021 (625 4700);
PAINT SKYBLUE (625 4700);
FORCEPROP 1 LAST PART_NUMBER D97712-004
R 1
J 0
(525 4700);
DISPLAY 0.617021 (525 4700);
PAINT BLUE (525 4700);
FORCEPROP 1 LAST PATH I4
J 0
(625 5050);
DISPLAY 0.978723 (625 5050);
PAINT WHITE (625 5050);
DISPLAY INVISIBLE (625 5050);
FORCEPROP 2 LAST CDS_LIB mstr_discrete
J 0
(575 4900);
PAINT MONO (575 4900);
DISPLAY INVISIBLE (575 4900);
FORCEPROP 2 LAST BOM_COST SM_CONTROLLER
J 0
(625 5050);
PAINT MONO (625 5050);
DISPLAY INVISIBLE (625 5050);
FORCEPROP 2 LAST ROOM BMC
J 0
(625 5050);
DISPLAY 1.510638 (625 5050);
PAINT ORANGE (625 5050);
DISPLAY INVISIBLE (625 5050);
FORCEPROP 1 LASTPIN (575 4800) $PN 2
J 0
(585 4780);
DISPLAY 0.787234 (585 4780);
PAINT ORANGE (585 4780);
DISPLAY INVISIBLE (585 4780);
FORCEPROP 1 LASTPIN (575 5000) $PN 1
J 0
(585 4980);
DISPLAY 0.787234 (585 4980);
PAINT ORANGE (585 4980);
DISPLAY INVISIBLE (585 4980);
FORCEADD P3V3_STBY..1
(-2650 3050);
FORCEPROP 3 LASTPIN (-2650 3000) SIG_NAME P3V3_STBY\g
J 0
(-2640 3010);
DISPLAY 0.659574 (-2640 3010);
PAINT MONO (-2640 3010);
DISPLAY INVISIBLE (-2640 3010);
FORCEPROP 1 LAST PATH I40
J 0
(-2605 3052);
DISPLAY 0.340426 (-2605 3052);
PAINT GREEN (-2605 3052);
DISPLAY INVISIBLE (-2605 3052);
FORCEPROP 1 LAST VOLTAGE 3.3V
J 0
(-2695 3007);
DISPLAY 0.340426 (-2695 3007);
PAINT GREEN (-2695 3007);
DISPLAY INVISIBLE (-2695 3007);
FORCEPROP 1 LAST SIZE 1B
J 0
(-2605 3072);
DISPLAY 0.340426 (-2605 3072);
PAINT GREEN (-2605 3072);
DISPLAY INVISIBLE (-2605 3072);
FORCEPROP 1 LAST BODY_TYPE PLUMBING
J 0
(-2695 3007);
DISPLAY 0.340426 (-2695 3007);
PAINT GREEN (-2695 3007);
DISPLAY INVISIBLE (-2695 3007);
FORCEPROP 1 LAST HDL_POWER P3V3_STBY
J 0
(-2950 2925);
DISPLAY 0.872340 (-2950 2925);
PAINT ORANGE (-2950 2925);
DISPLAY INVISIBLE (-2950 2925);
FORCEPROP 2 LAST CDS_LIB mstr_symbols
J 0
(-2650 3050);
PAINT MONO (-2650 3050);
DISPLAY INVISIBLE (-2650 3050);
FORCEADD P3V3_STBY..1
(-3025 5225);
FORCEPROP 3 LASTPIN (-3025 5175) SIG_NAME P3V3_STBY\g
J 0
(-3015 5185);
DISPLAY 0.659574 (-3015 5185);
PAINT MONO (-3015 5185);
DISPLAY INVISIBLE (-3015 5185);
FORCEPROP 1 LAST PATH I41
J 0
(-2980 5227);
DISPLAY 0.340426 (-2980 5227);
PAINT GREEN (-2980 5227);
DISPLAY INVISIBLE (-2980 5227);
FORCEPROP 1 LAST VOLTAGE 3.3V
J 0
(-3070 5182);
DISPLAY 0.340426 (-3070 5182);
PAINT GREEN (-3070 5182);
DISPLAY INVISIBLE (-3070 5182);
FORCEPROP 2 LAST CDS_LIB mstr_symbols
J 0
(-3025 5225);
PAINT MONO (-3025 5225);
DISPLAY INVISIBLE (-3025 5225);
FORCEPROP 1 LAST HDL_POWER P3V3_STBY
J 0
(-3325 5100);
DISPLAY 0.872340 (-3325 5100);
PAINT ORANGE (-3325 5100);
DISPLAY INVISIBLE (-3325 5100);
FORCEPROP 1 LAST BODY_TYPE PLUMBING
J 0
(-3070 5182);
DISPLAY 0.340426 (-3070 5182);
PAINT GREEN (-3070 5182);
DISPLAY INVISIBLE (-3070 5182);
FORCEPROP 1 LAST SIZE 1B
J 0
(-2980 5247);
DISPLAY 0.340426 (-2980 5247);
PAINT GREEN (-2980 5247);
DISPLAY INVISIBLE (-2980 5247);
FORCEADD W_VCC_CIRCLE..1
(-3100 4025);
FORCEPROP 3 LASTPIN (-3100 4025) SIG_NAME VCC_DACAV3V3\g
J 0
(-3090 4035);
DISPLAY 0.659574 (-3090 4035);
PAINT MONO (-3090 4035);
DISPLAY INVISIBLE (-3090 4035);
FORCEPROP 1 LAST HDL_POWER VCC_DACAV3V3
J 1
(-3079 4100);
DISPLAY 0.872340 (-3079 4100);
PAINT ORANGE (-3079 4100);
FORCEPROP 1 LAST PATH I42
J 0
(-3100 4025);
DISPLAY 0.617021 (-3100 4025);
PAINT GREEN (-3100 4025);
DISPLAY INVISIBLE (-3100 4025);
FORCEPROP 1 LAST BODY_TYPE PLUMBING
J 0
(-3088 4019);
DISPLAY 0.340426 (-3088 4019);
PAINT GREEN (-3088 4019);
DISPLAY INVISIBLE (-3088 4019);
FORCEPROP 1 LAST CDS_LMAN_SYM_OUTLINE -100,100,100,-100
J 0
(-3100 4025);
DISPLAY 0.468085 (-3100 4025);
PAINT GREEN (-3100 4025);
DISPLAY INVISIBLE (-3100 4025);
FORCEPROP 2 LAST CDS_LIB w_power
J 0
(-3100 4025);
PAINT MONO (-3100 4025);
DISPLAY INVISIBLE (-3100 4025);
FORCEADD SC4D7U10V3KX-GP..1
(-3675 4975);
FORCEPROP 1 LAST VALUE SC4D7U10V3KX-GP
J 0
(-3675 4900);
DISPLAY 0.617021 (-3675 4900);
PAINT GREEN (-3675 4900);
FORCEPROP 1 LAST LOCATION C25W30
J 0
(-3650 5005);
DISPLAY 0.617021 (-3650 5005);
PAINT GREEN (-3650 5005);
FORCEPROP 1 LAST PATH I43
J 0
(-3675 4975);
DISPLAY 0.617021 (-3675 4975);
PAINT GREEN (-3675 4975);
DISPLAY INVISIBLE (-3675 4975);
FORCEPROP 2 LAST CDS_LIB w_hdl
J 0
(-3675 4975);
PAINT MONO (-3675 4975);
DISPLAY INVISIBLE (-3675 4975);
FORCEPROP 1 LAST CDS_LMAN_SYM_OUTLINE -50,25,50,-25
J 0
(-3675 4975);
DISPLAY 0.468085 (-3675 4975);
PAINT GREEN (-3675 4975);
DISPLAY INVISIBLE (-3675 4975);
FORCEPROP 1 LAST PACK_TYPE SMD-BCG
J 0
(-3675 4975);
DISPLAY 0.617021 (-3675 4975);
PAINT GREEN (-3675 4975);
DISPLAY INVISIBLE (-3675 4975);
FORCEPROP 1 LAST PART_NUMBER 78.47523.5BL
J 0
(-3675 4975);
DISPLAY 0.617021 (-3675 4975);
PAINT GREEN (-3675 4975);
DISPLAY INVISIBLE (-3675 4975);
FORCEADD GND..1
(-3675 4500);
FORCEPROP 3 LASTPIN (-3675 4550) SIG_NAME GND\g
J 0
(-3665 4560);
DISPLAY 0.659574 (-3665 4560);
PAINT MONO (-3665 4560);
DISPLAY INVISIBLE (-3665 4560);
FORCEPROP 1 LAST PATH I44
J 0
(-3600 4500);
DISPLAY 0.872340 (-3600 4500);
PAINT AQUA (-3600 4500);
DISPLAY INVISIBLE (-3600 4500);
FORCEPROP 2 LAST CDS_LIB mstr_symbols
J 0
(-3675 4500);
PAINT ORANGE (-3675 4500);
DISPLAY INVISIBLE (-3675 4500);
FORCEPROP 1 LAST SIZE 1B
J 0
(-3600 4450);
DISPLAY 0.872340 (-3600 4450);
PAINT AQUA (-3600 4450);
DISPLAY INVISIBLE (-3600 4450);
FORCEPROP 1 LAST HDL_POWER GND
J 0
(-3675 4650);
DISPLAY 0.872340 (-3675 4650);
PAINT GREEN (-3675 4650);
DISPLAY INVISIBLE (-3675 4650);
FORCEPROP 1 LAST BODY_TYPE PLUMBING
J 0
(-3720 4457);
DISPLAY 0.340426 (-3720 4457);
PAINT GREEN (-3720 4457);
DISPLAY INVISIBLE (-3720 4457);
FORCEPROP 1 LAST VOLTAGE 0.0V
J 0
(-3720 4457);
DISPLAY 0.340426 (-3720 4457);
PAINT GREEN (-3720 4457);
DISPLAY INVISIBLE (-3720 4457);
FORCEADD CAP..1
(-4075 4975);
FORCEPROP 1 LAST LOCATION C25W29
J 0
(-4025 5075);
DISPLAY 0.617021 (-4025 5075);
PAINT AQUA (-4025 5075);
FORCEPROP 1 LAST PART_NUMBER C95333-007
J 0
(-4025 4825);
DISPLAY 0.617021 (-4025 4825);
PAINT BLUE (-4025 4825);
FORCEPROP 1 LASTPIN (-4075 4875) $PN 2
J 0
(-4065 4855);
DISPLAY 0.617021 (-4065 4855);
PAINT ORANGE (-4065 4855);
FORCEPROP 1 LAST MATERIAL X6S
J 0
(-4025 4875);
DISPLAY 0.617021 (-4025 4875);
PAINT SKYBLUE (-4025 4875);
FORCEPROP 1 LAST VOLTAGE 16V
J 0
(-4025 4975);
DISPLAY 0.617021 (-4025 4975);
PAINT SKYBLUE (-4025 4975);
FORCEPROP 1 LAST PACK_TYPE 0805
J 0
(-4025 4775);
DISPLAY 0.617021 (-4025 4775);
PAINT SKYBLUE (-4025 4775);
FORCEPROP 1 LAST TOLERANCE 10%
J 0
(-4025 4925);
DISPLAY 0.617021 (-4025 4925);
PAINT SKYBLUE (-4025 4925);
FORCEPROP 1 LASTPIN (-4075 5075) $PN 1
J 0
(-4065 5055);
DISPLAY 0.617021 (-4065 5055);
PAINT ORANGE (-4065 5055);
FORCEPROP 1 LAST VALUE 10UF
J 0
(-4025 5025);
DISPLAY 0.617021 (-4025 5025);
PAINT SKYBLUE (-4025 5025);
FORCEPROP 1 LAST PATH I45
J 0
(-4025 5125);
DISPLAY 0.978723 (-4025 5125);
PAINT WHITE (-4025 5125);
DISPLAY INVISIBLE (-4025 5125);
FORCEPROP 2 LAST CDS_LIB mstr_discrete
J 0
(-4075 4975);
PAINT ORANGE (-4075 4975);
DISPLAY INVISIBLE (-4075 4975);
FORCEPROP 0 LAST CDS_SEC 1
J 0
(-4025 5125);
PAINT MONO (-4025 5125);
DISPLAY INVISIBLE (-4025 5125);
FORCEPROP 2 LAST SEC_TYPE 0805
J 0
(-4025 5175);
DISPLAY 1.021277 (-4025 5175);
PAINT ORANGE (-4025 5175);
DISPLAY INVISIBLE (-4025 5175);
FORCEPROP 2 LAST SEC 1
J 0
(-4025 5175);
DISPLAY 0.680851 (-4025 5175);
PAINT MONO (-4025 5175);
DISPLAY INVISIBLE (-4025 5175);
FORCEPROP 0 LAST ROOM BMC
J 0
(-4025 5125);
DISPLAY 1.021277 (-4025 5125);
PAINT ORANGE (-4025 5125);
DISPLAY INVISIBLE (-4025 5125);
FORCEPROP 0 LAST BOM_COST SM_CONTROLLER
J 0
(-4025 5175);
DISPLAY 1.021277 (-4025 5175);
PAINT ORANGE (-4025 5175);
DISPLAY INVISIBLE (-4025 5175);
FORCEPROP 0 LAST CDS_LOCATION C25W29
J 0
(-4025 5125);
PAINT MONO (-4025 5125);
DISPLAY INVISIBLE (-4025 5125);
FORCEADD CAP..1
(-4475 4975);
FORCEPROP 1 LAST LOCATION C25W28
J 0
(-4425 5075);
DISPLAY 0.617021 (-4425 5075);
PAINT AQUA (-4425 5075);
FORCEPROP 1 LAST VALUE 1.0UF
J 0
(-4425 5000);
DISPLAY 0.617021 (-4425 5000);
PAINT SKYBLUE (-4425 5000);
FORCEPROP 1 LAST VOLTAGE 6.3V
J 0
(-4425 4925);
DISPLAY 0.617021 (-4425 4925);
PAINT SKYBLUE (-4425 4925);
FORCEPROP 1 LAST TOLERANCE 10%
J 0
(-4425 4875);
DISPLAY 0.617021 (-4425 4875);
PAINT SKYBLUE (-4425 4875);
FORCEPROP 1 LAST MATERIAL X6S
J 0
(-4425 4825);
DISPLAY 0.617021 (-4425 4825);
PAINT SKYBLUE (-4425 4825);
FORCEPROP 1 LAST PACK_TYPE 0402
J 0
(-4425 4775);
DISPLAY 0.617021 (-4425 4775);
PAINT SKYBLUE (-4425 4775);
FORCEPROP 1 LAST PART_NUMBER D97712-004
R 1
J 0
(-4525 4775);
DISPLAY 0.617021 (-4525 4775);
PAINT BLUE (-4525 4775);
FORCEPROP 1 LAST PATH I46
J 0
(-4425 5125);
DISPLAY 0.978723 (-4425 5125);
PAINT WHITE (-4425 5125);
DISPLAY INVISIBLE (-4425 5125);
FORCEPROP 2 LAST CDS_LIB mstr_discrete
J 0
(-4475 4975);
PAINT MONO (-4475 4975);
DISPLAY INVISIBLE (-4475 4975);
FORCEPROP 2 LAST BOM_COST SM_CONTROLLER
J 0
(-4425 5125);
PAINT MONO (-4425 5125);
DISPLAY INVISIBLE (-4425 5125);
FORCEPROP 2 LAST ROOM BMC
J 0
(-4425 5125);
DISPLAY 1.510638 (-4425 5125);
PAINT ORANGE (-4425 5125);
DISPLAY INVISIBLE (-4425 5125);
FORCEPROP 1 LASTPIN (-4475 4875) $PN 2
J 0
(-4465 4855);
DISPLAY 0.787234 (-4465 4855);
PAINT ORANGE (-4465 4855);
DISPLAY INVISIBLE (-4465 4855);
FORCEPROP 1 LASTPIN (-4475 5075) $PN 1
J 0
(-4465 5055);
DISPLAY 0.787234 (-4465 5055);
PAINT ORANGE (-4465 5055);
DISPLAY INVISIBLE (-4465 5055);
FORCEADD P3V3_STBY..1
(-4400 4000);
FORCEPROP 3 LASTPIN (-4400 3950) SIG_NAME P3V3_STBY\g
J 0
(-4390 3960);
DISPLAY 0.659574 (-4390 3960);
PAINT MONO (-4390 3960);
DISPLAY INVISIBLE (-4390 3960);
FORCEPROP 1 LAST PATH I47
J 0
(-4355 4002);
DISPLAY 0.340426 (-4355 4002);
PAINT GREEN (-4355 4002);
DISPLAY INVISIBLE (-4355 4002);
FORCEPROP 1 LAST VOLTAGE 3.3V
J 0
(-4445 3957);
DISPLAY 0.340426 (-4445 3957);
PAINT GREEN (-4445 3957);
DISPLAY INVISIBLE (-4445 3957);
FORCEPROP 2 LAST CDS_LIB mstr_symbols
J 0
(-4400 4000);
PAINT MONO (-4400 4000);
DISPLAY INVISIBLE (-4400 4000);
FORCEPROP 1 LAST HDL_POWER P3V3_STBY
J 0
(-4700 3875);
DISPLAY 0.872340 (-4700 3875);
PAINT ORANGE (-4700 3875);
DISPLAY INVISIBLE (-4700 3875);
FORCEPROP 1 LAST BODY_TYPE PLUMBING
J 0
(-4445 3957);
DISPLAY 0.340426 (-4445 3957);
PAINT GREEN (-4445 3957);
DISPLAY INVISIBLE (-4445 3957);
FORCEPROP 1 LAST SIZE 1B
J 0
(-4355 4022);
DISPLAY 0.340426 (-4355 4022);
PAINT GREEN (-4355 4022);
DISPLAY INVISIBLE (-4355 4022);
FORCEADD CAP..1
(-4875 4975);
FORCEPROP 1 LAST VALUE 1.0UF
J 0
(-4825 5000);
DISPLAY 0.617021 (-4825 5000);
PAINT SKYBLUE (-4825 5000);
FORCEPROP 1 LAST PART_NUMBER D97712-004
R 1
J 0
(-4925 4775);
DISPLAY 0.617021 (-4925 4775);
PAINT BLUE (-4925 4775);
FORCEPROP 1 LAST TOLERANCE 10%
J 0
(-4825 4875);
DISPLAY 0.617021 (-4825 4875);
PAINT SKYBLUE (-4825 4875);
FORCEPROP 1 LAST PACK_TYPE 0402
J 0
(-4825 4775);
DISPLAY 0.617021 (-4825 4775);
PAINT SKYBLUE (-4825 4775);
FORCEPROP 1 LAST MATERIAL X6S
J 0
(-4825 4825);
DISPLAY 0.617021 (-4825 4825);
PAINT SKYBLUE (-4825 4825);
FORCEPROP 1 LAST VOLTAGE 6.3V
J 0
(-4825 4925);
DISPLAY 0.617021 (-4825 4925);
PAINT SKYBLUE (-4825 4925);
FORCEPROP 1 LAST LOCATION C25W27
J 0
(-4825 5075);
DISPLAY 0.617021 (-4825 5075);
PAINT AQUA (-4825 5075);
FORCEPROP 1 LAST PATH I48
J 0
(-4825 5125);
DISPLAY 0.978723 (-4825 5125);
PAINT WHITE (-4825 5125);
DISPLAY INVISIBLE (-4825 5125);
FORCEPROP 2 LAST ROOM BMC
J 0
(-4825 5125);
DISPLAY 1.510638 (-4825 5125);
PAINT ORANGE (-4825 5125);
DISPLAY INVISIBLE (-4825 5125);
FORCEPROP 2 LAST BOM_COST SM_CONTROLLER
J 0
(-4825 5125);
PAINT MONO (-4825 5125);
DISPLAY INVISIBLE (-4825 5125);
FORCEPROP 2 LAST CDS_LIB mstr_discrete
J 0
(-4875 4975);
PAINT MONO (-4875 4975);
DISPLAY INVISIBLE (-4875 4975);
FORCEPROP 1 LASTPIN (-4875 4875) $PN 2
J 0
(-4865 4855);
DISPLAY 0.787234 (-4865 4855);
PAINT ORANGE (-4865 4855);
DISPLAY INVISIBLE (-4865 4855);
FORCEPROP 1 LASTPIN (-4875 5075) $PN 1
J 0
(-4865 5055);
DISPLAY 0.787234 (-4865 5055);
PAINT ORANGE (-4865 5055);
DISPLAY INVISIBLE (-4865 5055);
FORCEADD W_VCC_CIRCLE..1
(-4900 4050);
FORCEPROP 3 LASTPIN (-4900 4050) SIG_NAME VCC_ADCAV3V3\g
J 0
(-4890 4060);
DISPLAY 0.659574 (-4890 4060);
PAINT MONO (-4890 4060);
DISPLAY INVISIBLE (-4890 4060);
FORCEPROP 1 LAST HDL_POWER VCC_ADCAV3V3
J 1
(-4879 4125);
DISPLAY 0.872340 (-4879 4125);
PAINT ORANGE (-4879 4125);
FORCEPROP 1 LAST PATH I49
J 0
(-4900 4050);
DISPLAY 0.617021 (-4900 4050);
PAINT GREEN (-4900 4050);
DISPLAY INVISIBLE (-4900 4050);
FORCEPROP 1 LAST BODY_TYPE PLUMBING
J 0
(-4888 4044);
DISPLAY 0.340426 (-4888 4044);
PAINT GREEN (-4888 4044);
DISPLAY INVISIBLE (-4888 4044);
FORCEPROP 2 LAST CDS_LIB w_power
J 0
(-4900 4050);
PAINT MONO (-4900 4050);
DISPLAY INVISIBLE (-4900 4050);
FORCEPROP 1 LAST CDS_LMAN_SYM_OUTLINE -100,100,100,-100
J 0
(-4900 4050);
DISPLAY 0.468085 (-4900 4050);
PAINT GREEN (-4900 4050);
DISPLAY INVISIBLE (-4900 4050);
FORCEADD GND..1
(575 4475);
FORCEPROP 3 LASTPIN (575 4525) SIG_NAME GND\g
J 0
(585 4535);
DISPLAY 0.659574 (585 4535);
PAINT MONO (585 4535);
DISPLAY INVISIBLE (585 4535);
FORCEPROP 1 LAST PATH I5
J 0
(650 4475);
DISPLAY 0.872340 (650 4475);
PAINT AQUA (650 4475);
DISPLAY INVISIBLE (650 4475);
FORCEPROP 1 LAST HDL_POWER GND
J 0
(575 4625);
DISPLAY 0.872340 (575 4625);
PAINT GREEN (575 4625);
DISPLAY INVISIBLE (575 4625);
FORCEPROP 1 LAST SIZE 1B
J 0
(650 4425);
DISPLAY 0.872340 (650 4425);
PAINT AQUA (650 4425);
DISPLAY INVISIBLE (650 4425);
FORCEPROP 1 LAST BODY_TYPE PLUMBING
J 0
(530 4432);
DISPLAY 0.340426 (530 4432);
PAINT GREEN (530 4432);
DISPLAY INVISIBLE (530 4432);
FORCEPROP 1 LAST VOLTAGE 0.0V
J 0
(530 4432);
DISPLAY 0.340426 (530 4432);
PAINT GREEN (530 4432);
DISPLAY INVISIBLE (530 4432);
FORCEPROP 2 LAST CDS_LIB mstr_symbols
J 0
(575 4475);
PAINT MONO (575 4475);
DISPLAY INVISIBLE (575 4475);
FORCEADD SC4D7U10V3KX-GP..1
(-3100 3600);
FORCEPROP 1 LAST LOCATION C25W36
J 0
(-3075 3630);
DISPLAY 0.617021 (-3075 3630);
PAINT GREEN (-3075 3630);
FORCEPROP 1 LAST VALUE SC4D7U10V3KX-GP
J 0
(-3075 3550);
DISPLAY 0.617021 (-3075 3550);
PAINT GREEN (-3075 3550);
FORCEPROP 1 LAST PATH I50
J 0
(-3100 3600);
DISPLAY 0.617021 (-3100 3600);
PAINT GREEN (-3100 3600);
DISPLAY INVISIBLE (-3100 3600);
FORCEPROP 2 LAST CDS_LIB w_hdl
J 0
(-3100 3600);
PAINT MONO (-3100 3600);
DISPLAY INVISIBLE (-3100 3600);
FORCEPROP 1 LAST CDS_LMAN_SYM_OUTLINE -50,25,50,-25
J 0
(-3100 3600);
DISPLAY 0.468085 (-3100 3600);
PAINT GREEN (-3100 3600);
DISPLAY INVISIBLE (-3100 3600);
FORCEPROP 1 LAST PART_NUMBER 78.47523.5BL
J 0
(-3100 3600);
DISPLAY 0.617021 (-3100 3600);
PAINT GREEN (-3100 3600);
DISPLAY INVISIBLE (-3100 3600);
FORCEPROP 1 LAST PACK_TYPE SMD-BCG
J 0
(-3100 3600);
DISPLAY 0.617021 (-3100 3600);
PAINT GREEN (-3100 3600);
DISPLAY INVISIBLE (-3100 3600);
FORCEADD CAP..1
(-3450 3600);
FORCEPROP 1 LAST TOLERANCE 10%
J 0
(-3400 3500);
DISPLAY 0.617021 (-3400 3500);
PAINT SKYBLUE (-3400 3500);
FORCEPROP 1 LAST VOLTAGE 6.3V
J 0
(-3400 3550);
DISPLAY 0.617021 (-3400 3550);
PAINT SKYBLUE (-3400 3550);
FORCEPROP 1 LAST VALUE 1.0UF
J 0
(-3400 3625);
DISPLAY 0.617021 (-3400 3625);
PAINT SKYBLUE (-3400 3625);
FORCEPROP 1 LAST MATERIAL X6S
J 0
(-3400 3450);
DISPLAY 0.617021 (-3400 3450);
PAINT SKYBLUE (-3400 3450);
FORCEPROP 1 LAST PACK_TYPE 0402
J 0
(-3400 3400);
DISPLAY 0.617021 (-3400 3400);
PAINT SKYBLUE (-3400 3400);
FORCEPROP 1 LAST LOCATION C25W35
J 0
(-3400 3700);
DISPLAY 0.617021 (-3400 3700);
PAINT AQUA (-3400 3700);
FORCEPROP 1 LAST PART_NUMBER D97712-004
R 1
J 0
(-3250 3375);
DISPLAY 0.617021 (-3250 3375);
PAINT BLUE (-3250 3375);
FORCEPROP 1 LAST PATH I51
J 0
(-3400 3750);
DISPLAY 0.978723 (-3400 3750);
PAINT WHITE (-3400 3750);
DISPLAY INVISIBLE (-3400 3750);
FORCEPROP 2 LAST BOM_COST SM_CONTROLLER
J 0
(-3400 3750);
PAINT MONO (-3400 3750);
DISPLAY INVISIBLE (-3400 3750);
FORCEPROP 2 LAST ROOM BMC
J 0
(-3400 3750);
DISPLAY 1.510638 (-3400 3750);
PAINT ORANGE (-3400 3750);
DISPLAY INVISIBLE (-3400 3750);
FORCEPROP 2 LAST CDS_LIB mstr_discrete
J 0
(-3450 3600);
PAINT MONO (-3450 3600);
DISPLAY INVISIBLE (-3450 3600);
FORCEPROP 1 LASTPIN (-3450 3500) $PN 2
J 0
(-3440 3480);
DISPLAY 0.787234 (-3440 3480);
PAINT ORANGE (-3440 3480);
DISPLAY INVISIBLE (-3440 3480);
FORCEPROP 1 LASTPIN (-3450 3700) $PN 1
J 0
(-3440 3680);
DISPLAY 0.787234 (-3440 3680);
PAINT ORANGE (-3440 3680);
DISPLAY INVISIBLE (-3440 3680);
FORCEADD GND..1
(-3100 3050);
FORCEPROP 3 LASTPIN (-3100 3100) SIG_NAME GND\g
J 0
(-3090 3110);
DISPLAY 0.659574 (-3090 3110);
PAINT MONO (-3090 3110);
DISPLAY INVISIBLE (-3090 3110);
FORCEPROP 1 LAST PATH I52
J 0
(-3025 3050);
DISPLAY 0.872340 (-3025 3050);
PAINT AQUA (-3025 3050);
DISPLAY INVISIBLE (-3025 3050);
FORCEPROP 1 LAST VOLTAGE 0.0V
J 0
(-3145 3007);
DISPLAY 0.340426 (-3145 3007);
PAINT GREEN (-3145 3007);
DISPLAY INVISIBLE (-3145 3007);
FORCEPROP 1 LAST BODY_TYPE PLUMBING
J 0
(-3145 3007);
DISPLAY 0.340426 (-3145 3007);
PAINT GREEN (-3145 3007);
DISPLAY INVISIBLE (-3145 3007);
FORCEPROP 2 LAST CDS_LIB mstr_symbols
J 0
(-3100 3050);
PAINT MONO (-3100 3050);
DISPLAY INVISIBLE (-3100 3050);
FORCEPROP 1 LAST SIZE 1B
J 0
(-3025 3000);
DISPLAY 0.872340 (-3025 3000);
PAINT AQUA (-3025 3000);
DISPLAY INVISIBLE (-3025 3000);
FORCEPROP 1 LAST HDL_POWER GND
J 0
(-3100 3200);
DISPLAY 0.872340 (-3100 3200);
PAINT GREEN (-3100 3200);
DISPLAY INVISIBLE (-3100 3200);
FORCEADD SCD1U16V2KX-3GP..1
(-3800 3575);
FORCEPROP 1 LAST VALUE SCD1U16V2KX-3GP
J 0
(-3775 3525);
DISPLAY 0.617021 (-3775 3525);
PAINT GREEN (-3775 3525);
FORCEPROP 1 LAST LOCATION C25W34
J 0
(-3775 3605);
DISPLAY 0.617021 (-3775 3605);
PAINT GREEN (-3775 3605);
FORCEPROP 1 LAST PATH I53
J 0
(-3800 3575);
DISPLAY 0.617021 (-3800 3575);
PAINT GREEN (-3800 3575);
DISPLAY INVISIBLE (-3800 3575);
FORCEPROP 1 LAST CDS_LMAN_SYM_OUTLINE -50,25,50,-25
J 0
(-3800 3575);
DISPLAY 0.468085 (-3800 3575);
PAINT GREEN (-3800 3575);
DISPLAY INVISIBLE (-3800 3575);
FORCEPROP 2 LAST CDS_LIB w_hdl
J 0
(-3800 3575);
PAINT MONO (-3800 3575);
DISPLAY INVISIBLE (-3800 3575);
FORCEPROP 1 LAST PART_NUMBER 78.10421.2FL
J 0
(-3800 3575);
DISPLAY 0.617021 (-3800 3575);
PAINT GREEN (-3800 3575);
DISPLAY INVISIBLE (-3800 3575);
FORCEPROP 1 LAST PACK_TYPE SMD-BCG
J 0
(-3800 3575);
DISPLAY 0.617021 (-3800 3575);
PAINT GREEN (-3800 3575);
DISPLAY INVISIBLE (-3800 3575);
FORCEADD SC4D7U10V3KX-GP..1
(-3675 2500);
FORCEPROP 1 LAST LOCATION C25W47
J 0
(-3650 2530);
DISPLAY 0.617021 (-3650 2530);
PAINT GREEN (-3650 2530);
FORCEPROP 1 LAST VALUE SC4D7U10V3KX-GP
J 0
(-3650 2450);
DISPLAY 0.617021 (-3650 2450);
PAINT GREEN (-3650 2450);
FORCEPROP 1 LAST PATH I54
J 0
(-3675 2500);
DISPLAY 0.617021 (-3675 2500);
PAINT GREEN (-3675 2500);
DISPLAY INVISIBLE (-3675 2500);
FORCEPROP 1 LAST CDS_LMAN_SYM_OUTLINE -50,25,50,-25
J 0
(-3675 2500);
DISPLAY 0.468085 (-3675 2500);
PAINT GREEN (-3675 2500);
DISPLAY INVISIBLE (-3675 2500);
FORCEPROP 2 LAST CDS_LIB w_hdl
J 0
(-3675 2500);
PAINT MONO (-3675 2500);
DISPLAY INVISIBLE (-3675 2500);
FORCEPROP 1 LAST PART_NUMBER 78.47523.5BL
J 0
(-3675 2500);
DISPLAY 0.617021 (-3675 2500);
PAINT GREEN (-3675 2500);
DISPLAY INVISIBLE (-3675 2500);
FORCEPROP 1 LAST PACK_TYPE SMD-BCG
J 0
(-3675 2500);
DISPLAY 0.617021 (-3675 2500);
PAINT GREEN (-3675 2500);
DISPLAY INVISIBLE (-3675 2500);
FORCEADD CAP..1
(-3975 2475);
FORCEPROP 1 LAST VOLTAGE 16V
J 0
(-3925 2475);
DISPLAY 0.617021 (-3925 2475);
PAINT SKYBLUE (-3925 2475);
FORCEPROP 1 LAST TOLERANCE 10%
J 0
(-3925 2425);
DISPLAY 0.617021 (-3925 2425);
PAINT SKYBLUE (-3925 2425);
FORCEPROP 1 LAST PACK_TYPE 0805
J 0
(-3925 2275);
DISPLAY 0.617021 (-3925 2275);
PAINT SKYBLUE (-3925 2275);
FORCEPROP 1 LAST PART_NUMBER C95333-007
J 0
(-3925 2325);
DISPLAY 0.617021 (-3925 2325);
PAINT BLUE (-3925 2325);
FORCEPROP 1 LAST MATERIAL X6S
J 0
(-3925 2375);
DISPLAY 0.617021 (-3925 2375);
PAINT SKYBLUE (-3925 2375);
FORCEPROP 1 LAST VALUE 10UF
J 0
(-3925 2525);
DISPLAY 0.617021 (-3925 2525);
PAINT SKYBLUE (-3925 2525);
FORCEPROP 1 LAST LOCATION C25W46
J 0
(-3925 2575);
DISPLAY 0.617021 (-3925 2575);
PAINT AQUA (-3925 2575);
FORCEPROP 1 LAST PATH I55
J 0
(-3925 2625);
DISPLAY 0.978723 (-3925 2625);
PAINT WHITE (-3925 2625);
DISPLAY INVISIBLE (-3925 2625);
FORCEPROP 0 LAST BOM_COST SM_CONTROLLER
J 0
(-3925 2675);
DISPLAY 1.021277 (-3925 2675);
PAINT ORANGE (-3925 2675);
DISPLAY INVISIBLE (-3925 2675);
FORCEPROP 0 LAST ROOM BMC
J 0
(-3925 2625);
DISPLAY 1.021277 (-3925 2625);
PAINT ORANGE (-3925 2625);
DISPLAY INVISIBLE (-3925 2625);
FORCEPROP 2 LAST CDS_LIB mstr_discrete
J 0
(-3975 2475);
PAINT MONO (-3975 2475);
DISPLAY INVISIBLE (-3975 2475);
FORCEPROP 1 LASTPIN (-3975 2375) $PN 2
J 0
(-3965 2355);
DISPLAY 0.787234 (-3965 2355);
PAINT ORANGE (-3965 2355);
DISPLAY INVISIBLE (-3965 2355);
FORCEPROP 1 LASTPIN (-3975 2575) $PN 1
J 0
(-3965 2555);
DISPLAY 0.787234 (-3965 2555);
PAINT ORANGE (-3965 2555);
DISPLAY INVISIBLE (-3965 2555);
FORCEADD GND..1
(-3750 1975);
FORCEPROP 3 LASTPIN (-3750 2025) SIG_NAME GND\g
J 0
(-3740 2035);
DISPLAY 0.659574 (-3740 2035);
PAINT MONO (-3740 2035);
DISPLAY INVISIBLE (-3740 2035);
FORCEPROP 1 LAST PATH I56
J 0
(-3675 1975);
DISPLAY 0.872340 (-3675 1975);
PAINT AQUA (-3675 1975);
DISPLAY INVISIBLE (-3675 1975);
FORCEPROP 1 LAST VOLTAGE 0.0V
J 0
(-3795 1932);
DISPLAY 0.340426 (-3795 1932);
PAINT GREEN (-3795 1932);
DISPLAY INVISIBLE (-3795 1932);
FORCEPROP 1 LAST BODY_TYPE PLUMBING
J 0
(-3795 1932);
DISPLAY 0.340426 (-3795 1932);
PAINT GREEN (-3795 1932);
DISPLAY INVISIBLE (-3795 1932);
FORCEPROP 1 LAST SIZE 1B
J 0
(-3675 1925);
DISPLAY 0.872340 (-3675 1925);
PAINT AQUA (-3675 1925);
DISPLAY INVISIBLE (-3675 1925);
FORCEPROP 1 LAST HDL_POWER GND
J 0
(-3750 2125);
DISPLAY 0.872340 (-3750 2125);
PAINT GREEN (-3750 2125);
DISPLAY INVISIBLE (-3750 2125);
FORCEPROP 2 LAST CDS_LIB mstr_symbols
J 0
(-3750 1975);
PAINT MONO (-3750 1975);
DISPLAY INVISIBLE (-3750 1975);
FORCEADD 0R3J-0-U-GP..1
R 1
(-4075 3850);
FORCEPROP 1 LAST LOCATION R25W93
R 1
J 0
(-4155 3875);
DISPLAY 0.617021 (-4155 3875);
PAINT GREEN (-4155 3875);
FORCEPROP 1 LAST VALUE 0R3J-0-U-GP
R 1
J 0
(-3975 3875);
DISPLAY 0.617021 (-3975 3875);
PAINT GREEN (-3975 3875);
FORCEPROP 1 LAST PATH I57
R 1
J 0
(-4075 3850);
DISPLAY 0.617021 (-4075 3850);
PAINT GREEN (-4075 3850);
DISPLAY INVISIBLE (-4075 3850);
FORCEPROP 1 LAST PACK_TYPE RCL_GP
R 1
J 0
(-4075 3850);
DISPLAY 0.617021 (-4075 3850);
PAINT GREEN (-4075 3850);
DISPLAY INVISIBLE (-4075 3850);
FORCEPROP 1 LAST PART_NUMBER 63.00000.00L
R 1
J 0
(-4075 3850);
DISPLAY 0.617021 (-4075 3850);
PAINT GREEN (-4075 3850);
DISPLAY INVISIBLE (-4075 3850);
FORCEPROP 2 LAST CDS_LIB w_hdl
R 1
J 0
(-4075 3850);
PAINT MONO (-4075 3850);
DISPLAY INVISIBLE (-4075 3850);
FORCEPROP 1 LAST CDS_LMAN_SYM_OUTLINE -50,75,50,-75
R 1
J 0
(-4075 3850);
DISPLAY 0.468085 (-4075 3850);
PAINT GREEN (-4075 3850);
DISPLAY INVISIBLE (-4075 3850);
FORCEADD W_VCC_CIRCLE..1
(-4325 2925);
FORCEPROP 3 LASTPIN (-4325 2925) SIG_NAME VCC_D_3V3\g
J 0
(-4315 2935);
DISPLAY 0.659574 (-4315 2935);
PAINT MONO (-4315 2935);
DISPLAY INVISIBLE (-4315 2935);
FORCEPROP 1 LAST HDL_POWER VCC_D_3V3
J 1
(-4304 3000);
DISPLAY 0.872340 (-4304 3000);
PAINT ORANGE (-4304 3000);
FORCEPROP 1 LAST PATH I58
J 0
(-4325 2925);
DISPLAY 0.617021 (-4325 2925);
PAINT GREEN (-4325 2925);
DISPLAY INVISIBLE (-4325 2925);
FORCEPROP 1 LAST CDS_LMAN_SYM_OUTLINE -100,100,100,-100
J 0
(-4325 2925);
DISPLAY 0.468085 (-4325 2925);
PAINT GREEN (-4325 2925);
DISPLAY INVISIBLE (-4325 2925);
FORCEPROP 2 LAST CDS_LIB w_power
J 0
(-4325 2925);
PAINT MONO (-4325 2925);
DISPLAY INVISIBLE (-4325 2925);
FORCEPROP 1 LAST BODY_TYPE PLUMBING
J 0
(-4313 2919);
DISPLAY 0.340426 (-4313 2919);
PAINT GREEN (-4313 2919);
DISPLAY INVISIBLE (-4313 2919);
FORCEADD CAP..1
(-4900 3700);
FORCEPROP 1 LAST VOLTAGE 6.3V
J 0
(-4850 3650);
DISPLAY 0.617021 (-4850 3650);
PAINT SKYBLUE (-4850 3650);
FORCEPROP 1 LAST MATERIAL X6S
J 0
(-4850 3550);
DISPLAY 0.617021 (-4850 3550);
PAINT SKYBLUE (-4850 3550);
FORCEPROP 1 LAST PACK_TYPE 0402
J 0
(-4850 3500);
DISPLAY 0.617021 (-4850 3500);
PAINT SKYBLUE (-4850 3500);
FORCEPROP 1 LAST TOLERANCE 10%
J 0
(-4850 3600);
DISPLAY 0.617021 (-4850 3600);
PAINT SKYBLUE (-4850 3600);
FORCEPROP 1 LAST PART_NUMBER D97712-004
R 1
J 0
(-4950 3500);
DISPLAY 0.617021 (-4950 3500);
PAINT BLUE (-4950 3500);
FORCEPROP 1 LAST LOCATION C25W33
J 0
(-4850 3800);
DISPLAY 0.617021 (-4850 3800);
PAINT AQUA (-4850 3800);
FORCEPROP 1 LAST VALUE 1.0UF
J 0
(-4850 3725);
DISPLAY 0.617021 (-4850 3725);
PAINT SKYBLUE (-4850 3725);
FORCEPROP 1 LAST PATH I59
J 0
(-4850 3850);
DISPLAY 0.978723 (-4850 3850);
PAINT WHITE (-4850 3850);
DISPLAY INVISIBLE (-4850 3850);
FORCEPROP 2 LAST CDS_LIB mstr_discrete
J 0
(-4900 3700);
PAINT MONO (-4900 3700);
DISPLAY INVISIBLE (-4900 3700);
FORCEPROP 2 LAST ROOM BMC
J 0
(-4850 3850);
DISPLAY 1.510638 (-4850 3850);
PAINT ORANGE (-4850 3850);
DISPLAY INVISIBLE (-4850 3850);
FORCEPROP 2 LAST BOM_COST SM_CONTROLLER
J 0
(-4850 3850);
PAINT MONO (-4850 3850);
DISPLAY INVISIBLE (-4850 3850);
FORCEPROP 1 LASTPIN (-4900 3600) $PN 2
J 0
(-4890 3580);
DISPLAY 0.787234 (-4890 3580);
PAINT ORANGE (-4890 3580);
DISPLAY INVISIBLE (-4890 3580);
FORCEPROP 1 LASTPIN (-4900 3800) $PN 1
J 0
(-4890 3780);
DISPLAY 0.787234 (-4890 3780);
PAINT ORANGE (-4890 3780);
DISPLAY INVISIBLE (-4890 3780);
FORCEADD SC4D7U10V3KX-GP..1
(75 4875);
FORCEPROP 1 LAST VALUE SC4D7U10V3KX-GP
J 0
(100 4825);
DISPLAY 0.617021 (100 4825);
PAINT GREEN (100 4825);
FORCEPROP 1 LAST LOCATION C25W70
J 0
(100 4905);
DISPLAY 0.617021 (100 4905);
PAINT GREEN (100 4905);
FORCEPROP 1 LAST PATH I6
J 0
(75 4875);
DISPLAY 0.617021 (75 4875);
PAINT GREEN (75 4875);
DISPLAY INVISIBLE (75 4875);
FORCEPROP 1 LAST PART_NUMBER 78.47523.5BL
J 0
(75 4875);
DISPLAY 0.617021 (75 4875);
PAINT GREEN (75 4875);
DISPLAY INVISIBLE (75 4875);
FORCEPROP 1 LAST PACK_TYPE SMD-BCG
J 0
(75 4875);
DISPLAY 0.617021 (75 4875);
PAINT GREEN (75 4875);
DISPLAY INVISIBLE (75 4875);
FORCEPROP 1 LAST CDS_LMAN_SYM_OUTLINE -50,25,50,-25
J 0
(75 4875);
DISPLAY 0.468085 (75 4875);
PAINT GREEN (75 4875);
DISPLAY INVISIBLE (75 4875);
FORCEPROP 2 LAST CDS_LIB w_hdl
J 0
(75 4875);
PAINT MONO (75 4875);
DISPLAY INVISIBLE (75 4875);
FORCEADD GND..1
(-4900 3175);
FORCEPROP 3 LASTPIN (-4900 3225) SIG_NAME GND\g
J 0
(-4890 3235);
DISPLAY 0.659574 (-4890 3235);
PAINT MONO (-4890 3235);
DISPLAY INVISIBLE (-4890 3235);
FORCEPROP 1 LAST PATH I60
J 0
(-4825 3175);
DISPLAY 0.872340 (-4825 3175);
PAINT AQUA (-4825 3175);
DISPLAY INVISIBLE (-4825 3175);
FORCEPROP 1 LAST VOLTAGE 0.0V
J 0
(-4945 3132);
DISPLAY 0.340426 (-4945 3132);
PAINT GREEN (-4945 3132);
DISPLAY INVISIBLE (-4945 3132);
FORCEPROP 1 LAST BODY_TYPE PLUMBING
J 0
(-4945 3132);
DISPLAY 0.340426 (-4945 3132);
PAINT GREEN (-4945 3132);
DISPLAY INVISIBLE (-4945 3132);
FORCEPROP 2 LAST CDS_LIB mstr_symbols
J 0
(-4900 3175);
PAINT MONO (-4900 3175);
DISPLAY INVISIBLE (-4900 3175);
FORCEPROP 1 LAST SIZE 1B
J 0
(-4825 3125);
DISPLAY 0.872340 (-4825 3125);
PAINT AQUA (-4825 3125);
DISPLAY INVISIBLE (-4825 3125);
FORCEPROP 1 LAST HDL_POWER GND
J 0
(-4900 3325);
DISPLAY 0.872340 (-4900 3325);
PAINT GREEN (-4900 3325);
DISPLAY INVISIBLE (-4900 3325);
FORCEADD SCD1U16V2KX-3GP..1
(-4325 2500);
FORCEPROP 1 LAST VALUE SCD1U16V2KX-3GP
J 0
(-4300 2450);
DISPLAY 0.617021 (-4300 2450);
PAINT GREEN (-4300 2450);
FORCEPROP 1 LAST LOCATION C25W45
J 0
(-4300 2530);
DISPLAY 0.617021 (-4300 2530);
PAINT GREEN (-4300 2530);
FORCEPROP 1 LAST PATH I61
J 0
(-4325 2500);
DISPLAY 0.617021 (-4325 2500);
PAINT GREEN (-4325 2500);
DISPLAY INVISIBLE (-4325 2500);
FORCEPROP 1 LAST CDS_LMAN_SYM_OUTLINE -50,25,50,-25
J 0
(-4325 2500);
DISPLAY 0.468085 (-4325 2500);
PAINT GREEN (-4325 2500);
DISPLAY INVISIBLE (-4325 2500);
FORCEPROP 2 LAST CDS_LIB w_hdl
J 0
(-4325 2500);
PAINT MONO (-4325 2500);
DISPLAY INVISIBLE (-4325 2500);
FORCEPROP 1 LAST PACK_TYPE SMD-BCG
J 0
(-4325 2500);
DISPLAY 0.617021 (-4325 2500);
PAINT GREEN (-4325 2500);
DISPLAY INVISIBLE (-4325 2500);
FORCEPROP 1 LAST PART_NUMBER 78.10421.2FL
J 0
(-4325 2500);
DISPLAY 0.617021 (-4325 2500);
PAINT GREEN (-4325 2500);
DISPLAY INVISIBLE (-4325 2500);
FORCEADD CAP..1
(-4575 2475);
FORCEPROP 1 LAST PACK_TYPE 0402
J 0
(-4525 2275);
DISPLAY 0.617021 (-4525 2275);
PAINT SKYBLUE (-4525 2275);
FORCEPROP 1 LAST PART_NUMBER D97712-004
R 1
J 0
(-4625 2275);
DISPLAY 0.617021 (-4625 2275);
PAINT BLUE (-4625 2275);
FORCEPROP 1 LAST MATERIAL X6S
J 0
(-4525 2325);
DISPLAY 0.617021 (-4525 2325);
PAINT SKYBLUE (-4525 2325);
FORCEPROP 1 LAST TOLERANCE 10%
J 0
(-4525 2375);
DISPLAY 0.617021 (-4525 2375);
PAINT SKYBLUE (-4525 2375);
FORCEPROP 1 LAST LOCATION C25W44
J 0
(-4525 2575);
DISPLAY 0.617021 (-4525 2575);
PAINT AQUA (-4525 2575);
FORCEPROP 1 LAST VALUE 1.0UF
J 0
(-4525 2500);
DISPLAY 0.617021 (-4525 2500);
PAINT SKYBLUE (-4525 2500);
FORCEPROP 1 LAST VOLTAGE 6.3V
J 0
(-4525 2425);
DISPLAY 0.617021 (-4525 2425);
PAINT SKYBLUE (-4525 2425);
FORCEPROP 1 LAST PATH I62
J 0
(-4525 2625);
DISPLAY 0.978723 (-4525 2625);
PAINT WHITE (-4525 2625);
DISPLAY INVISIBLE (-4525 2625);
FORCEPROP 2 LAST ROOM BMC
J 0
(-4525 2625);
DISPLAY 1.510638 (-4525 2625);
PAINT ORANGE (-4525 2625);
DISPLAY INVISIBLE (-4525 2625);
FORCEPROP 2 LAST BOM_COST SM_CONTROLLER
J 0
(-4525 2625);
PAINT MONO (-4525 2625);
DISPLAY INVISIBLE (-4525 2625);
FORCEPROP 2 LAST CDS_LIB mstr_discrete
J 0
(-4575 2475);
PAINT MONO (-4575 2475);
DISPLAY INVISIBLE (-4575 2475);
FORCEPROP 1 LASTPIN (-4575 2375) $PN 2
J 0
(-4565 2355);
DISPLAY 0.787234 (-4565 2355);
PAINT ORANGE (-4565 2355);
DISPLAY INVISIBLE (-4565 2355);
FORCEPROP 1 LASTPIN (-4575 2575) $PN 1
J 0
(-4565 2555);
DISPLAY 0.787234 (-4565 2555);
PAINT ORANGE (-4565 2555);
DISPLAY INVISIBLE (-4565 2555);
FORCEADD CAP..1
(-4875 2475);
FORCEPROP 1 LAST MATERIAL X6S
J 0
(-4825 2325);
DISPLAY 0.617021 (-4825 2325);
PAINT SKYBLUE (-4825 2325);
FORCEPROP 1 LAST TOLERANCE 10%
J 0
(-4825 2375);
DISPLAY 0.617021 (-4825 2375);
PAINT SKYBLUE (-4825 2375);
FORCEPROP 1 LAST VALUE 1.0UF
J 0
(-4825 2500);
DISPLAY 0.617021 (-4825 2500);
PAINT SKYBLUE (-4825 2500);
FORCEPROP 1 LAST LOCATION C25W43
J 0
(-4825 2575);
DISPLAY 0.617021 (-4825 2575);
PAINT AQUA (-4825 2575);
FORCEPROP 1 LAST VOLTAGE 6.3V
J 0
(-4825 2425);
DISPLAY 0.617021 (-4825 2425);
PAINT SKYBLUE (-4825 2425);
FORCEPROP 1 LAST PART_NUMBER D97712-004
R 1
J 0
(-4925 2275);
DISPLAY 0.617021 (-4925 2275);
PAINT BLUE (-4925 2275);
FORCEPROP 1 LAST PACK_TYPE 0402
J 0
(-4825 2275);
DISPLAY 0.617021 (-4825 2275);
PAINT SKYBLUE (-4825 2275);
FORCEPROP 1 LAST PATH I63
J 0
(-4825 2625);
DISPLAY 0.978723 (-4825 2625);
PAINT WHITE (-4825 2625);
DISPLAY INVISIBLE (-4825 2625);
FORCEPROP 2 LAST ROOM BMC
J 0
(-4825 2625);
DISPLAY 1.510638 (-4825 2625);
PAINT ORANGE (-4825 2625);
DISPLAY INVISIBLE (-4825 2625);
FORCEPROP 2 LAST BOM_COST SM_CONTROLLER
J 0
(-4825 2625);
PAINT MONO (-4825 2625);
DISPLAY INVISIBLE (-4825 2625);
FORCEPROP 2 LAST CDS_LIB mstr_discrete
J 0
(-4875 2475);
PAINT MONO (-4875 2475);
DISPLAY INVISIBLE (-4875 2475);
FORCEPROP 1 LASTPIN (-4875 2375) $PN 2
J 0
(-4865 2355);
DISPLAY 0.787234 (-4865 2355);
PAINT ORANGE (-4865 2355);
DISPLAY INVISIBLE (-4865 2355);
FORCEPROP 1 LASTPIN (-4875 2575) $PN 1
J 0
(-4865 2555);
DISPLAY 0.787234 (-4865 2555);
PAINT ORANGE (-4865 2555);
DISPLAY INVISIBLE (-4865 2555);
FORCEADD W_VCC_CIRCLE..1
(-4775 1875);
FORCEPROP 3 LASTPIN (-4775 1875) SIG_NAME VCC_PA_3V3\g
J 0
(-4765 1885);
DISPLAY 0.659574 (-4765 1885);
PAINT MONO (-4765 1885);
DISPLAY INVISIBLE (-4765 1885);
FORCEPROP 1 LAST HDL_POWER VCC_PA_3V3
J 1
(-4754 1950);
DISPLAY 0.872340 (-4754 1950);
PAINT ORANGE (-4754 1950);
FORCEPROP 1 LAST PATH I64
J 0
(-4775 1875);
DISPLAY 0.617021 (-4775 1875);
PAINT GREEN (-4775 1875);
DISPLAY INVISIBLE (-4775 1875);
FORCEPROP 2 LAST CDS_LIB w_power
J 0
(-4775 1875);
PAINT MONO (-4775 1875);
DISPLAY INVISIBLE (-4775 1875);
FORCEPROP 1 LAST CDS_LMAN_SYM_OUTLINE -100,100,100,-100
J 0
(-4775 1875);
DISPLAY 0.468085 (-4775 1875);
PAINT GREEN (-4775 1875);
DISPLAY INVISIBLE (-4775 1875);
FORCEPROP 1 LAST BODY_TYPE PLUMBING
J 0
(-4763 1869);
DISPLAY 0.340426 (-4763 1869);
PAINT GREEN (-4763 1869);
DISPLAY INVISIBLE (-4763 1869);
FORCEADD SC4D7U10V3KX-GP..1
(-1800 1325);
FORCEPROP 1 LAST LOCATION C25W62
J 0
(-1775 1355);
DISPLAY 0.617021 (-1775 1355);
PAINT GREEN (-1775 1355);
FORCEPROP 1 LAST VALUE SC4D7U10V3KX-GP
J 0
(-1775 1275);
DISPLAY 0.617021 (-1775 1275);
PAINT GREEN (-1775 1275);
FORCEPROP 1 LAST PATH I65
J 0
(-1800 1325);
DISPLAY 0.617021 (-1800 1325);
PAINT GREEN (-1800 1325);
DISPLAY INVISIBLE (-1800 1325);
FORCEPROP 2 LAST CDS_LIB w_hdl
J 0
(-1800 1325);
PAINT MONO (-1800 1325);
DISPLAY INVISIBLE (-1800 1325);
FORCEPROP 1 LAST CDS_LMAN_SYM_OUTLINE -50,25,50,-25
J 0
(-1800 1325);
DISPLAY 0.468085 (-1800 1325);
PAINT GREEN (-1800 1325);
DISPLAY INVISIBLE (-1800 1325);
FORCEPROP 1 LAST PART_NUMBER 78.47523.5BL
J 0
(-1800 1325);
DISPLAY 0.617021 (-1800 1325);
PAINT GREEN (-1800 1325);
DISPLAY INVISIBLE (-1800 1325);
FORCEPROP 1 LAST PACK_TYPE SMD-BCG
J 0
(-1800 1325);
DISPLAY 0.617021 (-1800 1325);
PAINT GREEN (-1800 1325);
DISPLAY INVISIBLE (-1800 1325);
FORCEADD GND..1
(-1800 950);
FORCEPROP 3 LASTPIN (-1800 1000) SIG_NAME GND\g
J 0
(-1790 1010);
DISPLAY 0.659574 (-1790 1010);
PAINT MONO (-1790 1010);
DISPLAY INVISIBLE (-1790 1010);
FORCEPROP 1 LAST PATH I66
J 0
(-1725 950);
DISPLAY 0.872340 (-1725 950);
PAINT AQUA (-1725 950);
DISPLAY INVISIBLE (-1725 950);
FORCEPROP 1 LAST VOLTAGE 0.0V
J 0
(-1845 907);
DISPLAY 0.340426 (-1845 907);
PAINT GREEN (-1845 907);
DISPLAY INVISIBLE (-1845 907);
FORCEPROP 1 LAST BODY_TYPE PLUMBING
J 0
(-1845 907);
DISPLAY 0.340426 (-1845 907);
PAINT GREEN (-1845 907);
DISPLAY INVISIBLE (-1845 907);
FORCEPROP 2 LAST CDS_LIB mstr_symbols
J 0
(-1800 950);
PAINT MONO (-1800 950);
DISPLAY INVISIBLE (-1800 950);
FORCEPROP 1 LAST HDL_POWER GND
J 0
(-1800 1100);
DISPLAY 0.872340 (-1800 1100);
PAINT GREEN (-1800 1100);
DISPLAY INVISIBLE (-1800 1100);
FORCEPROP 1 LAST SIZE 1B
J 0
(-1725 900);
DISPLAY 0.872340 (-1725 900);
PAINT AQUA (-1725 900);
DISPLAY INVISIBLE (-1725 900);
FORCEADD SCD1U16V2KX-3GP..1
(-2200 1325);
FORCEPROP 1 LAST LOCATION C25W61
J 0
(-2175 1355);
DISPLAY 0.617021 (-2175 1355);
PAINT GREEN (-2175 1355);
FORCEPROP 1 LAST VALUE SCD1U16V2KX-3GP
J 0
(-2175 1275);
DISPLAY 0.617021 (-2175 1275);
PAINT GREEN (-2175 1275);
FORCEPROP 1 LAST PATH I67
J 0
(-2200 1325);
DISPLAY 0.617021 (-2200 1325);
PAINT GREEN (-2200 1325);
DISPLAY INVISIBLE (-2200 1325);
FORCEPROP 2 LAST CDS_LIB w_hdl
J 0
(-2200 1325);
PAINT MONO (-2200 1325);
DISPLAY INVISIBLE (-2200 1325);
FORCEPROP 1 LAST CDS_LMAN_SYM_OUTLINE -50,25,50,-25
J 0
(-2200 1325);
DISPLAY 0.468085 (-2200 1325);
PAINT GREEN (-2200 1325);
DISPLAY INVISIBLE (-2200 1325);
FORCEPROP 1 LAST PART_NUMBER 78.10421.2FL
J 0
(-2200 1325);
DISPLAY 0.617021 (-2200 1325);
PAINT GREEN (-2200 1325);
DISPLAY INVISIBLE (-2200 1325);
FORCEPROP 1 LAST PACK_TYPE SMD-BCG
J 0
(-2200 1325);
DISPLAY 0.617021 (-2200 1325);
PAINT GREEN (-2200 1325);
DISPLAY INVISIBLE (-2200 1325);
FORCEADD P3V3_STBY..1
(-3500 1800);
FORCEPROP 3 LASTPIN (-3500 1750) SIG_NAME P3V3_STBY\g
J 0
(-3490 1760);
DISPLAY 0.659574 (-3490 1760);
PAINT MONO (-3490 1760);
DISPLAY INVISIBLE (-3490 1760);
FORCEPROP 1 LAST PATH I68
J 0
(-3455 1802);
DISPLAY 0.340426 (-3455 1802);
PAINT GREEN (-3455 1802);
DISPLAY INVISIBLE (-3455 1802);
FORCEPROP 1 LAST VOLTAGE 3.3V
J 0
(-3545 1757);
DISPLAY 0.340426 (-3545 1757);
PAINT GREEN (-3545 1757);
DISPLAY INVISIBLE (-3545 1757);
FORCEPROP 2 LAST CDS_LIB mstr_symbols
J 0
(-3500 1800);
PAINT MONO (-3500 1800);
DISPLAY INVISIBLE (-3500 1800);
FORCEPROP 1 LAST SIZE 1B
J 0
(-3455 1822);
DISPLAY 0.340426 (-3455 1822);
PAINT GREEN (-3455 1822);
DISPLAY INVISIBLE (-3455 1822);
FORCEPROP 1 LAST BODY_TYPE PLUMBING
J 0
(-3545 1757);
DISPLAY 0.340426 (-3545 1757);
PAINT GREEN (-3545 1757);
DISPLAY INVISIBLE (-3545 1757);
FORCEPROP 1 LAST HDL_POWER P3V3_STBY
J 0
(-3800 1675);
DISPLAY 0.872340 (-3800 1675);
PAINT ORANGE (-3800 1675);
DISPLAY INVISIBLE (-3800 1675);
FORCEADD SC4D7U10V3KX-GP..1
(-4775 1400);
FORCEPROP 1 LAST LOCATION C25W59
J 0
(-4750 1430);
DISPLAY 0.617021 (-4750 1430);
PAINT GREEN (-4750 1430);
FORCEPROP 1 LAST VALUE SC4D7U10V3KX-GP
J 0
(-4750 1350);
DISPLAY 0.617021 (-4750 1350);
PAINT GREEN (-4750 1350);
FORCEPROP 1 LAST PATH I69
J 0
(-4775 1400);
DISPLAY 0.617021 (-4775 1400);
PAINT GREEN (-4775 1400);
DISPLAY INVISIBLE (-4775 1400);
FORCEPROP 2 LAST CDS_LIB w_hdl
J 0
(-4775 1400);
PAINT MONO (-4775 1400);
DISPLAY INVISIBLE (-4775 1400);
FORCEPROP 1 LAST CDS_LMAN_SYM_OUTLINE -50,25,50,-25
J 0
(-4775 1400);
DISPLAY 0.468085 (-4775 1400);
PAINT GREEN (-4775 1400);
DISPLAY INVISIBLE (-4775 1400);
FORCEPROP 1 LAST PACK_TYPE SMD-BCG
J 0
(-4775 1400);
DISPLAY 0.617021 (-4775 1400);
PAINT GREEN (-4775 1400);
DISPLAY INVISIBLE (-4775 1400);
FORCEPROP 1 LAST PART_NUMBER 78.47523.5BL
J 0
(-4775 1400);
DISPLAY 0.617021 (-4775 1400);
PAINT GREEN (-4775 1400);
DISPLAY INVISIBLE (-4775 1400);
FORCEADD 0R3J-0-U-GP..1
R 1
(-100 5075);
FORCEPROP 1 LAST VALUE 0R3J-0-U-GP
J 0
(-250 5000);
DISPLAY 0.617021 (-250 5000);
PAINT GREEN (-250 5000);
FORCEPROP 1 LAST LOCATION R25W120
J 0
(-180 5100);
DISPLAY 0.617021 (-180 5100);
PAINT GREEN (-180 5100);
FORCEPROP 1 LAST PATH I7
R 1
J 0
(-100 5075);
DISPLAY 0.617021 (-100 5075);
PAINT GREEN (-100 5075);
DISPLAY INVISIBLE (-100 5075);
FORCEPROP 1 LAST PACK_TYPE RCL_GP
R 1
J 0
(-100 5075);
DISPLAY 0.617021 (-100 5075);
PAINT GREEN (-100 5075);
DISPLAY INVISIBLE (-100 5075);
FORCEPROP 1 LAST PART_NUMBER 63.00000.00L
R 1
J 0
(-100 5075);
DISPLAY 0.617021 (-100 5075);
PAINT GREEN (-100 5075);
DISPLAY INVISIBLE (-100 5075);
FORCEPROP 1 LAST CDS_LMAN_SYM_OUTLINE -50,75,50,-75
R 1
J 0
(-100 5075);
DISPLAY 0.468085 (-100 5075);
PAINT GREEN (-100 5075);
DISPLAY INVISIBLE (-100 5075);
FORCEPROP 2 LAST CDS_LIB w_hdl
J 0
(-100 5075);
PAINT MONO (-100 5075);
DISPLAY INVISIBLE (-100 5075);
FORCEADD GND..1
(-4775 925);
FORCEPROP 3 LASTPIN (-4775 975) SIG_NAME GND\g
J 0
(-4765 985);
DISPLAY 0.659574 (-4765 985);
PAINT MONO (-4765 985);
DISPLAY INVISIBLE (-4765 985);
FORCEPROP 1 LAST PATH I70
J 0
(-4700 925);
DISPLAY 0.872340 (-4700 925);
PAINT AQUA (-4700 925);
DISPLAY INVISIBLE (-4700 925);
FORCEPROP 1 LAST VOLTAGE 0.0V
J 0
(-4820 882);
DISPLAY 0.340426 (-4820 882);
PAINT GREEN (-4820 882);
DISPLAY INVISIBLE (-4820 882);
FORCEPROP 1 LAST BODY_TYPE PLUMBING
J 0
(-4820 882);
DISPLAY 0.340426 (-4820 882);
PAINT GREEN (-4820 882);
DISPLAY INVISIBLE (-4820 882);
FORCEPROP 2 LAST CDS_LIB mstr_symbols
J 0
(-4775 925);
PAINT MONO (-4775 925);
DISPLAY INVISIBLE (-4775 925);
FORCEPROP 1 LAST HDL_POWER GND
J 0
(-4775 1075);
DISPLAY 0.872340 (-4775 1075);
PAINT GREEN (-4775 1075);
DISPLAY INVISIBLE (-4775 1075);
FORCEPROP 1 LAST SIZE 1B
J 0
(-4700 875);
DISPLAY 0.872340 (-4700 875);
PAINT AQUA (-4700 875);
DISPLAY INVISIBLE (-4700 875);
FORCEADD CAP..1
(-5275 4975);
FORCEPROP 1 LAST VALUE 1.0UF
J 0
(-5225 5000);
DISPLAY 0.617021 (-5225 5000);
PAINT SKYBLUE (-5225 5000);
FORCEPROP 1 LAST VOLTAGE 6.3V
J 0
(-5225 4925);
DISPLAY 0.617021 (-5225 4925);
PAINT SKYBLUE (-5225 4925);
FORCEPROP 1 LAST MATERIAL X6S
J 0
(-5225 4825);
DISPLAY 0.617021 (-5225 4825);
PAINT SKYBLUE (-5225 4825);
FORCEPROP 1 LAST PACK_TYPE 0402
J 0
(-5225 4775);
DISPLAY 0.617021 (-5225 4775);
PAINT SKYBLUE (-5225 4775);
FORCEPROP 1 LAST PART_NUMBER D97712-004
R 1
J 0
(-5325 4775);
DISPLAY 0.617021 (-5325 4775);
PAINT BLUE (-5325 4775);
FORCEPROP 1 LAST TOLERANCE 10%
J 0
(-5225 4875);
DISPLAY 0.617021 (-5225 4875);
PAINT SKYBLUE (-5225 4875);
FORCEPROP 1 LAST LOCATION C25W26
J 0
(-5225 5075);
DISPLAY 0.617021 (-5225 5075);
PAINT AQUA (-5225 5075);
FORCEPROP 1 LAST PATH I71
J 0
(-5225 5125);
DISPLAY 0.978723 (-5225 5125);
PAINT WHITE (-5225 5125);
DISPLAY INVISIBLE (-5225 5125);
FORCEPROP 2 LAST BOM_COST SM_CONTROLLER
J 0
(-5225 5125);
PAINT MONO (-5225 5125);
DISPLAY INVISIBLE (-5225 5125);
FORCEPROP 2 LAST ROOM BMC
J 0
(-5225 5125);
DISPLAY 1.510638 (-5225 5125);
PAINT ORANGE (-5225 5125);
DISPLAY INVISIBLE (-5225 5125);
FORCEPROP 2 LAST CDS_LIB mstr_discrete
J 0
(-5275 4975);
PAINT MONO (-5275 4975);
DISPLAY INVISIBLE (-5275 4975);
FORCEPROP 1 LASTPIN (-5275 4875) $PN 2
J 0
(-5265 4855);
DISPLAY 0.787234 (-5265 4855);
PAINT ORANGE (-5265 4855);
DISPLAY INVISIBLE (-5265 4855);
FORCEPROP 1 LASTPIN (-5275 5075) $PN 1
J 0
(-5265 5055);
DISPLAY 0.787234 (-5265 5055);
PAINT ORANGE (-5265 5055);
DISPLAY INVISIBLE (-5265 5055);
FORCEADD CAP..1
(-5675 4975);
FORCEPROP 1 LAST LOCATION C25W25
J 0
(-5625 5075);
DISPLAY 0.617021 (-5625 5075);
PAINT AQUA (-5625 5075);
FORCEPROP 1 LASTPIN (-5675 5075) $PN 1
J 0
(-5665 5055);
DISPLAY 0.617021 (-5665 5055);
PAINT ORANGE (-5665 5055);
FORCEPROP 1 LAST VALUE 1.0UF
J 0
(-5625 5000);
DISPLAY 0.617021 (-5625 5000);
PAINT SKYBLUE (-5625 5000);
FORCEPROP 1 LAST VOLTAGE 6.3V
J 0
(-5625 4925);
DISPLAY 0.617021 (-5625 4925);
PAINT SKYBLUE (-5625 4925);
FORCEPROP 1 LAST TOLERANCE 10%
J 0
(-5625 4875);
DISPLAY 0.617021 (-5625 4875);
PAINT SKYBLUE (-5625 4875);
FORCEPROP 1 LAST MATERIAL X6S
J 0
(-5625 4825);
DISPLAY 0.617021 (-5625 4825);
PAINT SKYBLUE (-5625 4825);
FORCEPROP 1 LAST PACK_TYPE 0402
J 0
(-5625 4775);
DISPLAY 0.617021 (-5625 4775);
PAINT SKYBLUE (-5625 4775);
FORCEPROP 1 LASTPIN (-5675 4875) $PN 2
J 0
(-5665 4855);
DISPLAY 0.617021 (-5665 4855);
PAINT ORANGE (-5665 4855);
FORCEPROP 1 LAST PART_NUMBER D97712-004
R 1
J 0
(-5725 4775);
DISPLAY 0.617021 (-5725 4775);
PAINT BLUE (-5725 4775);
FORCEPROP 1 LAST PATH I72
J 0
(-5625 5125);
DISPLAY 0.978723 (-5625 5125);
PAINT WHITE (-5625 5125);
DISPLAY INVISIBLE (-5625 5125);
FORCEPROP 0 LAST CDS_SEC 1
J 0
(-5625 5125);
PAINT MONO (-5625 5125);
DISPLAY INVISIBLE (-5625 5125);
FORCEPROP 2 LAST SEC 1
J 0
(-5625 5175);
DISPLAY 0.680851 (-5625 5175);
PAINT MONO (-5625 5175);
DISPLAY INVISIBLE (-5625 5175);
FORCEPROP 2 LAST SEC_TYPE 0402
J 0
(-5625 5175);
DISPLAY 1.021277 (-5625 5175);
PAINT ORANGE (-5625 5175);
DISPLAY INVISIBLE (-5625 5175);
FORCEPROP 2 LAST ROOM BMC
J 0
(-5625 5125);
DISPLAY 1.510638 (-5625 5125);
PAINT ORANGE (-5625 5125);
DISPLAY INVISIBLE (-5625 5125);
FORCEPROP 2 LAST BOM_COST SM_CONTROLLER
J 0
(-5625 5125);
PAINT MONO (-5625 5125);
DISPLAY INVISIBLE (-5625 5125);
FORCEPROP 2 LAST CDS_LIB mstr_discrete
J 0
(-5675 4975);
PAINT ORANGE (-5675 4975);
DISPLAY INVISIBLE (-5675 4975);
FORCEPROP 0 LAST CDS_LOCATION C25W25
J 0
(-5625 5125);
PAINT MONO (-5625 5125);
DISPLAY INVISIBLE (-5625 5125);
FORCEADD CAP..1
(-6075 4975);
FORCEPROP 1 LAST LOCATION C25W24
J 0
(-6025 5075);
DISPLAY 0.617021 (-6025 5075);
PAINT AQUA (-6025 5075);
FORCEPROP 1 LAST TOLERANCE 10%
J 0
(-6025 4875);
DISPLAY 0.617021 (-6025 4875);
PAINT SKYBLUE (-6025 4875);
FORCEPROP 1 LAST VOLTAGE 6.3V
J 0
(-6025 4925);
DISPLAY 0.617021 (-6025 4925);
PAINT SKYBLUE (-6025 4925);
FORCEPROP 1 LAST MATERIAL X6S
J 0
(-6025 4825);
DISPLAY 0.617021 (-6025 4825);
PAINT SKYBLUE (-6025 4825);
FORCEPROP 1 LASTPIN (-6075 5075) $PN 1
J 0
(-6065 5055);
DISPLAY 0.617021 (-6065 5055);
PAINT ORANGE (-6065 5055);
FORCEPROP 1 LASTPIN (-6075 4875) $PN 2
J 0
(-6065 4855);
DISPLAY 0.617021 (-6065 4855);
PAINT ORANGE (-6065 4855);
FORCEPROP 1 LAST VALUE 1.0UF
J 0
(-6025 5000);
DISPLAY 0.617021 (-6025 5000);
PAINT SKYBLUE (-6025 5000);
FORCEPROP 1 LAST PACK_TYPE 0402
J 0
(-6025 4775);
DISPLAY 0.617021 (-6025 4775);
PAINT SKYBLUE (-6025 4775);
FORCEPROP 1 LAST PART_NUMBER D97712-004
R 1
J 0
(-6125 4775);
DISPLAY 0.617021 (-6125 4775);
PAINT BLUE (-6125 4775);
FORCEPROP 1 LAST PATH I73
J 0
(-6025 5125);
DISPLAY 0.978723 (-6025 5125);
PAINT WHITE (-6025 5125);
DISPLAY INVISIBLE (-6025 5125);
FORCEPROP 0 LAST CDS_SEC 1
J 0
(-6025 5125);
PAINT MONO (-6025 5125);
DISPLAY INVISIBLE (-6025 5125);
FORCEPROP 2 LAST SEC 1
J 0
(-6025 5175);
DISPLAY 0.680851 (-6025 5175);
PAINT MONO (-6025 5175);
DISPLAY INVISIBLE (-6025 5175);
FORCEPROP 2 LAST SEC_TYPE 0402
J 0
(-6025 5175);
DISPLAY 1.021277 (-6025 5175);
PAINT ORANGE (-6025 5175);
DISPLAY INVISIBLE (-6025 5175);
FORCEPROP 2 LAST BOM_COST SM_CONTROLLER
J 0
(-6025 5125);
PAINT MONO (-6025 5125);
DISPLAY INVISIBLE (-6025 5125);
FORCEPROP 2 LAST ROOM BMC
J 0
(-6025 5125);
DISPLAY 1.510638 (-6025 5125);
PAINT ORANGE (-6025 5125);
DISPLAY INVISIBLE (-6025 5125);
FORCEPROP 2 LAST CDS_LIB mstr_discrete
J 0
(-6075 4975);
PAINT ORANGE (-6075 4975);
DISPLAY INVISIBLE (-6075 4975);
FORCEPROP 0 LAST CDS_LOCATION C25W24
J 0
(-6025 5125);
PAINT MONO (-6025 5125);
DISPLAY INVISIBLE (-6025 5125);
FORCEADD W_VCC_CIRCLE..1
(-6475 5200);
FORCEPROP 3 LASTPIN (-6475 5200) SIG_NAME P1V15_AUX_BMC\g
J 0
(-6465 5210);
DISPLAY 0.659574 (-6465 5210);
PAINT MONO (-6465 5210);
DISPLAY INVISIBLE (-6465 5210);
FORCEPROP 1 LAST HDL_POWER P1V15_AUX_BMC
J 1
(-6454 5275);
DISPLAY 0.872340 (-6454 5275);
PAINT ORANGE (-6454 5275);
FORCEPROP 1 LAST PATH I74
J 0
(-6475 5200);
DISPLAY 0.617021 (-6475 5200);
PAINT GREEN (-6475 5200);
DISPLAY INVISIBLE (-6475 5200);
FORCEPROP 2 LAST CDS_LIB w_power
J 0
(-6475 5200);
PAINT MONO (-6475 5200);
DISPLAY INVISIBLE (-6475 5200);
FORCEPROP 1 LAST CDS_LMAN_SYM_OUTLINE -100,100,100,-100
J 0
(-6475 5200);
DISPLAY 0.468085 (-6475 5200);
PAINT GREEN (-6475 5200);
DISPLAY INVISIBLE (-6475 5200);
FORCEPROP 1 LAST BODY_TYPE PLUMBING
J 0
(-6463 5194);
DISPLAY 0.340426 (-6463 5194);
PAINT GREEN (-6463 5194);
DISPLAY INVISIBLE (-6463 5194);
FORCEADD CAP..1
(-6475 4975);
FORCEPROP 1 LASTPIN (-6475 5075) $PN 1
J 0
(-6465 5055);
DISPLAY 0.617021 (-6465 5055);
PAINT ORANGE (-6465 5055);
FORCEPROP 1 LAST TOLERANCE 10%
J 0
(-6425 4875);
DISPLAY 0.617021 (-6425 4875);
PAINT SKYBLUE (-6425 4875);
FORCEPROP 1 LAST VOLTAGE 6.3V
J 0
(-6425 4925);
DISPLAY 0.617021 (-6425 4925);
PAINT SKYBLUE (-6425 4925);
FORCEPROP 1 LAST PART_NUMBER D97712-004
R 1
J 0
(-6525 4775);
DISPLAY 0.617021 (-6525 4775);
PAINT BLUE (-6525 4775);
FORCEPROP 1 LAST PACK_TYPE 0402
J 0
(-6425 4775);
DISPLAY 0.617021 (-6425 4775);
PAINT SKYBLUE (-6425 4775);
FORCEPROP 1 LAST MATERIAL X6S
J 0
(-6425 4825);
DISPLAY 0.617021 (-6425 4825);
PAINT SKYBLUE (-6425 4825);
FORCEPROP 1 LASTPIN (-6475 4875) $PN 2
J 0
(-6465 4855);
DISPLAY 0.617021 (-6465 4855);
PAINT ORANGE (-6465 4855);
FORCEPROP 1 LAST VALUE 1.0UF
J 0
(-6425 5000);
DISPLAY 0.617021 (-6425 5000);
PAINT SKYBLUE (-6425 5000);
FORCEPROP 1 LAST LOCATION C25W23
J 0
(-6425 5075);
DISPLAY 0.617021 (-6425 5075);
PAINT AQUA (-6425 5075);
FORCEPROP 1 LAST PATH I75
J 0
(-6425 5125);
DISPLAY 0.978723 (-6425 5125);
PAINT WHITE (-6425 5125);
DISPLAY INVISIBLE (-6425 5125);
FORCEPROP 0 LAST CDS_SEC 1
J 0
(-6425 5125);
PAINT MONO (-6425 5125);
DISPLAY INVISIBLE (-6425 5125);
FORCEPROP 2 LAST SEC 1
J 0
(-6425 5175);
DISPLAY 0.680851 (-6425 5175);
PAINT MONO (-6425 5175);
DISPLAY INVISIBLE (-6425 5175);
FORCEPROP 2 LAST SEC_TYPE 0402
J 0
(-6425 5175);
DISPLAY 1.021277 (-6425 5175);
PAINT ORANGE (-6425 5175);
DISPLAY INVISIBLE (-6425 5175);
FORCEPROP 2 LAST BOM_COST SM_CONTROLLER
J 0
(-6425 5125);
PAINT MONO (-6425 5125);
DISPLAY INVISIBLE (-6425 5125);
FORCEPROP 2 LAST CDS_LIB mstr_discrete
J 0
(-6475 4975);
PAINT ORANGE (-6475 4975);
DISPLAY INVISIBLE (-6475 4975);
FORCEPROP 2 LAST ROOM BMC
J 0
(-6425 5125);
DISPLAY 1.510638 (-6425 5125);
PAINT ORANGE (-6425 5125);
DISPLAY INVISIBLE (-6425 5125);
FORCEPROP 0 LAST CDS_LOCATION C25W23
J 0
(-6425 5125);
PAINT MONO (-6425 5125);
DISPLAY INVISIBLE (-6425 5125);
FORCEADD HCB1608KF-800T30-GP..1
R 1
(-6300 3975);
FORCEPROP 1 LAST VALUE HCB1608KF-800T30-GP
J 0
(-6400 3900);
DISPLAY 0.617021 (-6400 3900);
PAINT GREEN (-6400 3900);
FORCEPROP 1 LAST LOCATION FB2T3
J 0
(-6375 4025);
DISPLAY 0.617021 (-6375 4025);
PAINT GREEN (-6375 4025);
FORCEPROP 1 LAST PATH I76
R 1
J 0
(-6300 3975);
DISPLAY 0.617021 (-6300 3975);
PAINT GREEN (-6300 3975);
DISPLAY INVISIBLE (-6300 3975);
FORCEPROP 1 LAST PACK_TYPE DISCRET-G9
R 1
J 0
(-6300 3975);
DISPLAY 0.617021 (-6300 3975);
PAINT GREEN (-6300 3975);
DISPLAY INVISIBLE (-6300 3975);
FORCEPROP 1 LAST PART_NUMBER 68.00230.231
R 1
J 0
(-6300 3975);
DISPLAY 0.617021 (-6300 3975);
PAINT GREEN (-6300 3975);
DISPLAY INVISIBLE (-6300 3975);
FORCEPROP 2 LAST CDS_LIB w_hdl
R 1
J 0
(-6300 3975);
PAINT MONO (-6300 3975);
DISPLAY INVISIBLE (-6300 3975);
FORCEPROP 1 LAST CDS_LMAN_SYM_OUTLINE -50,100,50,-100
R 1
J 0
(-6300 3975);
DISPLAY 0.468085 (-6300 3975);
PAINT GREEN (-6300 3975);
DISPLAY INVISIBLE (-6300 3975);
FORCEADD P3V3_STBY..1
(-6575 4125);
FORCEPROP 3 LASTPIN (-6575 4075) SIG_NAME P3V3_STBY\g
J 0
(-6565 4085);
DISPLAY 0.659574 (-6565 4085);
PAINT MONO (-6565 4085);
DISPLAY INVISIBLE (-6565 4085);
FORCEPROP 1 LAST PATH I77
J 0
(-6530 4127);
DISPLAY 0.340426 (-6530 4127);
PAINT GREEN (-6530 4127);
DISPLAY INVISIBLE (-6530 4127);
FORCEPROP 1 LAST HDL_POWER P3V3_STBY
J 0
(-6875 4000);
DISPLAY 0.872340 (-6875 4000);
PAINT ORANGE (-6875 4000);
DISPLAY INVISIBLE (-6875 4000);
FORCEPROP 1 LAST BODY_TYPE PLUMBING
J 0
(-6620 4082);
DISPLAY 0.340426 (-6620 4082);
PAINT GREEN (-6620 4082);
DISPLAY INVISIBLE (-6620 4082);
FORCEPROP 1 LAST SIZE 1B
J 0
(-6530 4147);
DISPLAY 0.340426 (-6530 4147);
PAINT GREEN (-6530 4147);
DISPLAY INVISIBLE (-6530 4147);
FORCEPROP 2 LAST CDS_LIB mstr_symbols
J 0
(-6575 4125);
PAINT MONO (-6575 4125);
DISPLAY INVISIBLE (-6575 4125);
FORCEPROP 1 LAST VOLTAGE 3.3V
J 0
(-6620 4082);
DISPLAY 0.340426 (-6620 4082);
PAINT GREEN (-6620 4082);
DISPLAY INVISIBLE (-6620 4082);
FORCEADD CAP..1
(-5250 3725);
FORCEPROP 1 LAST LOCATION C25W32
J 0
(-5200 3825);
DISPLAY 0.617021 (-5200 3825);
PAINT AQUA (-5200 3825);
FORCEPROP 1 LAST VALUE 1.0UF
J 0
(-5200 3750);
DISPLAY 0.617021 (-5200 3750);
PAINT SKYBLUE (-5200 3750);
FORCEPROP 1 LAST VOLTAGE 6.3V
J 0
(-5200 3675);
DISPLAY 0.617021 (-5200 3675);
PAINT SKYBLUE (-5200 3675);
FORCEPROP 1 LAST TOLERANCE 10%
J 0
(-5200 3625);
DISPLAY 0.617021 (-5200 3625);
PAINT SKYBLUE (-5200 3625);
FORCEPROP 1 LAST MATERIAL X6S
J 0
(-5200 3575);
DISPLAY 0.617021 (-5200 3575);
PAINT SKYBLUE (-5200 3575);
FORCEPROP 1 LAST PACK_TYPE 0402
J 0
(-5200 3525);
DISPLAY 0.617021 (-5200 3525);
PAINT SKYBLUE (-5200 3525);
FORCEPROP 1 LAST PART_NUMBER D97712-004
R 1
J 0
(-5300 3525);
DISPLAY 0.617021 (-5300 3525);
PAINT BLUE (-5300 3525);
FORCEPROP 1 LAST PATH I78
J 0
(-5200 3875);
DISPLAY 0.978723 (-5200 3875);
PAINT WHITE (-5200 3875);
DISPLAY INVISIBLE (-5200 3875);
FORCEPROP 2 LAST CDS_LIB mstr_discrete
J 0
(-5250 3725);
PAINT MONO (-5250 3725);
DISPLAY INVISIBLE (-5250 3725);
FORCEPROP 2 LAST ROOM BMC
J 0
(-5200 3875);
DISPLAY 1.510638 (-5200 3875);
PAINT ORANGE (-5200 3875);
DISPLAY INVISIBLE (-5200 3875);
FORCEPROP 2 LAST BOM_COST SM_CONTROLLER
J 0
(-5200 3875);
PAINT MONO (-5200 3875);
DISPLAY INVISIBLE (-5200 3875);
FORCEPROP 1 LASTPIN (-5250 3625) $PN 2
J 0
(-5240 3605);
DISPLAY 0.787234 (-5240 3605);
PAINT ORANGE (-5240 3605);
DISPLAY INVISIBLE (-5240 3605);
FORCEPROP 1 LASTPIN (-5250 3825) $PN 1
J 0
(-5240 3805);
DISPLAY 0.787234 (-5240 3805);
PAINT ORANGE (-5240 3805);
DISPLAY INVISIBLE (-5240 3805);
FORCEADD SCD1U16V2KX-3GP..1
(-5700 3700);
FORCEPROP 1 LAST VALUE SCD1U16V2KX-3GP
J 0
(-5675 3650);
DISPLAY 0.617021 (-5675 3650);
PAINT GREEN (-5675 3650);
FORCEPROP 1 LAST LOCATION C25W31
J 0
(-5675 3730);
DISPLAY 0.617021 (-5675 3730);
PAINT GREEN (-5675 3730);
FORCEPROP 1 LAST PATH I79
J 0
(-5700 3700);
DISPLAY 0.617021 (-5700 3700);
PAINT GREEN (-5700 3700);
DISPLAY INVISIBLE (-5700 3700);
FORCEPROP 2 LAST CDS_LIB w_hdl
J 0
(-5700 3700);
PAINT MONO (-5700 3700);
DISPLAY INVISIBLE (-5700 3700);
FORCEPROP 1 LAST CDS_LMAN_SYM_OUTLINE -50,25,50,-25
J 0
(-5700 3700);
DISPLAY 0.468085 (-5700 3700);
PAINT GREEN (-5700 3700);
DISPLAY INVISIBLE (-5700 3700);
FORCEPROP 1 LAST PACK_TYPE SMD-BCG
J 0
(-5700 3700);
DISPLAY 0.617021 (-5700 3700);
PAINT GREEN (-5700 3700);
DISPLAY INVISIBLE (-5700 3700);
FORCEPROP 1 LAST PART_NUMBER 78.10421.2FL
J 0
(-5700 3700);
DISPLAY 0.617021 (-5700 3700);
PAINT GREEN (-5700 3700);
DISPLAY INVISIBLE (-5700 3700);
FORCEADD P3V3_STBY..1
(-425 5225);
FORCEPROP 3 LASTPIN (-425 5175) SIG_NAME P3V3_STBY\g
J 0
(-415 5185);
DISPLAY 0.659574 (-415 5185);
PAINT MONO (-415 5185);
DISPLAY INVISIBLE (-415 5185);
FORCEPROP 1 LAST PATH I8
J 0
(-380 5227);
DISPLAY 0.340426 (-380 5227);
PAINT GREEN (-380 5227);
DISPLAY INVISIBLE (-380 5227);
FORCEPROP 1 LAST VOLTAGE 3.3V
J 0
(-470 5182);
DISPLAY 0.340426 (-470 5182);
PAINT GREEN (-470 5182);
DISPLAY INVISIBLE (-470 5182);
FORCEPROP 1 LAST HDL_POWER P3V3_STBY
J 0
(-725 5100);
DISPLAY 0.872340 (-725 5100);
PAINT ORANGE (-725 5100);
DISPLAY INVISIBLE (-725 5100);
FORCEPROP 1 LAST BODY_TYPE PLUMBING
J 0
(-470 5182);
DISPLAY 0.340426 (-470 5182);
PAINT GREEN (-470 5182);
DISPLAY INVISIBLE (-470 5182);
FORCEPROP 1 LAST SIZE 1B
J 0
(-380 5247);
DISPLAY 0.340426 (-380 5247);
PAINT GREEN (-380 5247);
DISPLAY INVISIBLE (-380 5247);
FORCEPROP 2 LAST CDS_LIB mstr_symbols
J 0
(-425 5225);
PAINT MONO (-425 5225);
DISPLAY INVISIBLE (-425 5225);
FORCEADD CAP..1
(-5125 2475);
FORCEPROP 1 LAST TOLERANCE 10%
J 0
(-5075 2375);
DISPLAY 0.617021 (-5075 2375);
PAINT SKYBLUE (-5075 2375);
FORCEPROP 1 LAST MATERIAL X6S
J 0
(-5075 2325);
DISPLAY 0.617021 (-5075 2325);
PAINT SKYBLUE (-5075 2325);
FORCEPROP 1 LAST PACK_TYPE 0402
J 0
(-5075 2275);
DISPLAY 0.617021 (-5075 2275);
PAINT SKYBLUE (-5075 2275);
FORCEPROP 1 LAST LOCATION C25W42
J 0
(-5075 2575);
DISPLAY 0.617021 (-5075 2575);
PAINT AQUA (-5075 2575);
FORCEPROP 1 LAST VALUE 1.0UF
J 0
(-5075 2500);
DISPLAY 0.617021 (-5075 2500);
PAINT SKYBLUE (-5075 2500);
FORCEPROP 1 LAST VOLTAGE 6.3V
J 0
(-5075 2425);
DISPLAY 0.617021 (-5075 2425);
PAINT SKYBLUE (-5075 2425);
FORCEPROP 1 LAST PART_NUMBER D97712-004
R 1
J 0
(-5175 2275);
DISPLAY 0.617021 (-5175 2275);
PAINT BLUE (-5175 2275);
FORCEPROP 1 LAST PATH I80
J 0
(-5075 2625);
DISPLAY 0.978723 (-5075 2625);
PAINT WHITE (-5075 2625);
DISPLAY INVISIBLE (-5075 2625);
FORCEPROP 2 LAST CDS_LIB mstr_discrete
J 0
(-5125 2475);
PAINT MONO (-5125 2475);
DISPLAY INVISIBLE (-5125 2475);
FORCEPROP 2 LAST BOM_COST SM_CONTROLLER
J 0
(-5075 2625);
PAINT MONO (-5075 2625);
DISPLAY INVISIBLE (-5075 2625);
FORCEPROP 2 LAST ROOM BMC
J 0
(-5075 2625);
DISPLAY 1.510638 (-5075 2625);
PAINT ORANGE (-5075 2625);
DISPLAY INVISIBLE (-5075 2625);
FORCEPROP 1 LASTPIN (-5125 2375) $PN 2
J 0
(-5115 2355);
DISPLAY 0.787234 (-5115 2355);
PAINT ORANGE (-5115 2355);
DISPLAY INVISIBLE (-5115 2355);
FORCEPROP 1 LASTPIN (-5125 2575) $PN 1
J 0
(-5115 2555);
DISPLAY 0.787234 (-5115 2555);
PAINT ORANGE (-5115 2555);
DISPLAY INVISIBLE (-5115 2555);
FORCEADD CAP..1
(-5375 2475);
FORCEPROP 1 LAST PACK_TYPE 0402
J 0
(-5325 2275);
DISPLAY 0.617021 (-5325 2275);
PAINT SKYBLUE (-5325 2275);
FORCEPROP 1 LAST MATERIAL X6S
J 0
(-5325 2325);
DISPLAY 0.617021 (-5325 2325);
PAINT SKYBLUE (-5325 2325);
FORCEPROP 1 LAST TOLERANCE 10%
J 0
(-5325 2375);
DISPLAY 0.617021 (-5325 2375);
PAINT SKYBLUE (-5325 2375);
FORCEPROP 1 LAST LOCATION C25W41
J 0
(-5325 2575);
DISPLAY 0.617021 (-5325 2575);
PAINT AQUA (-5325 2575);
FORCEPROP 1 LAST PART_NUMBER D97712-004
R 1
J 0
(-5425 2275);
DISPLAY 0.617021 (-5425 2275);
PAINT BLUE (-5425 2275);
FORCEPROP 1 LAST VOLTAGE 6.3V
J 0
(-5325 2425);
DISPLAY 0.617021 (-5325 2425);
PAINT SKYBLUE (-5325 2425);
FORCEPROP 1 LAST VALUE 1.0UF
J 0
(-5325 2500);
DISPLAY 0.617021 (-5325 2500);
PAINT SKYBLUE (-5325 2500);
FORCEPROP 1 LAST PATH I81
J 0
(-5325 2625);
DISPLAY 0.978723 (-5325 2625);
PAINT WHITE (-5325 2625);
DISPLAY INVISIBLE (-5325 2625);
FORCEPROP 2 LAST CDS_LIB mstr_discrete
J 0
(-5375 2475);
PAINT MONO (-5375 2475);
DISPLAY INVISIBLE (-5375 2475);
FORCEPROP 2 LAST BOM_COST SM_CONTROLLER
J 0
(-5325 2625);
PAINT MONO (-5325 2625);
DISPLAY INVISIBLE (-5325 2625);
FORCEPROP 2 LAST ROOM BMC
J 0
(-5325 2625);
DISPLAY 1.510638 (-5325 2625);
PAINT ORANGE (-5325 2625);
DISPLAY INVISIBLE (-5325 2625);
FORCEPROP 1 LASTPIN (-5375 2375) $PN 2
J 0
(-5365 2355);
DISPLAY 0.787234 (-5365 2355);
PAINT ORANGE (-5365 2355);
DISPLAY INVISIBLE (-5365 2355);
FORCEPROP 1 LASTPIN (-5375 2575) $PN 1
J 0
(-5365 2555);
DISPLAY 0.787234 (-5365 2555);
PAINT ORANGE (-5365 2555);
DISPLAY INVISIBLE (-5365 2555);
FORCEADD CAP..1
(-5675 2475);
FORCEPROP 1 LAST PACK_TYPE 0402
J 0
(-5625 2275);
DISPLAY 0.617021 (-5625 2275);
PAINT SKYBLUE (-5625 2275);
FORCEPROP 1 LAST MATERIAL X6S
J 0
(-5625 2325);
DISPLAY 0.617021 (-5625 2325);
PAINT SKYBLUE (-5625 2325);
FORCEPROP 1 LAST TOLERANCE 10%
J 0
(-5625 2375);
DISPLAY 0.617021 (-5625 2375);
PAINT SKYBLUE (-5625 2375);
FORCEPROP 1 LAST VOLTAGE 6.3V
J 0
(-5625 2425);
DISPLAY 0.617021 (-5625 2425);
PAINT SKYBLUE (-5625 2425);
FORCEPROP 1 LAST PART_NUMBER D97712-004
R 1
J 0
(-5725 2275);
DISPLAY 0.617021 (-5725 2275);
PAINT BLUE (-5725 2275);
FORCEPROP 1 LAST VALUE 1.0UF
J 0
(-5625 2500);
DISPLAY 0.617021 (-5625 2500);
PAINT SKYBLUE (-5625 2500);
FORCEPROP 1 LAST LOCATION C25W40
J 0
(-5625 2575);
DISPLAY 0.617021 (-5625 2575);
PAINT AQUA (-5625 2575);
FORCEPROP 1 LAST PATH I82
J 0
(-5625 2625);
DISPLAY 0.978723 (-5625 2625);
PAINT WHITE (-5625 2625);
DISPLAY INVISIBLE (-5625 2625);
FORCEPROP 2 LAST BOM_COST SM_CONTROLLER
J 0
(-5625 2625);
PAINT MONO (-5625 2625);
DISPLAY INVISIBLE (-5625 2625);
FORCEPROP 2 LAST ROOM BMC
J 0
(-5625 2625);
DISPLAY 1.510638 (-5625 2625);
PAINT ORANGE (-5625 2625);
DISPLAY INVISIBLE (-5625 2625);
FORCEPROP 2 LAST CDS_LIB mstr_discrete
J 0
(-5675 2475);
PAINT MONO (-5675 2475);
DISPLAY INVISIBLE (-5675 2475);
FORCEPROP 1 LASTPIN (-5675 2375) $PN 2
J 0
(-5665 2355);
DISPLAY 0.787234 (-5665 2355);
PAINT ORANGE (-5665 2355);
DISPLAY INVISIBLE (-5665 2355);
FORCEPROP 1 LASTPIN (-5675 2575) $PN 1
J 0
(-5665 2555);
DISPLAY 0.787234 (-5665 2555);
PAINT ORANGE (-5665 2555);
DISPLAY INVISIBLE (-5665 2555);
FORCEADD P3V3_STBY..1
(-6550 2925);
FORCEPROP 3 LASTPIN (-6550 2875) SIG_NAME P3V3_STBY\g
J 0
(-6540 2885);
DISPLAY 0.659574 (-6540 2885);
PAINT MONO (-6540 2885);
DISPLAY INVISIBLE (-6540 2885);
FORCEPROP 1 LAST PATH I83
J 0
(-6505 2927);
DISPLAY 0.340426 (-6505 2927);
PAINT GREEN (-6505 2927);
DISPLAY INVISIBLE (-6505 2927);
FORCEPROP 1 LAST SIZE 1B
J 0
(-6505 2947);
DISPLAY 0.340426 (-6505 2947);
PAINT GREEN (-6505 2947);
DISPLAY INVISIBLE (-6505 2947);
FORCEPROP 1 LAST BODY_TYPE PLUMBING
J 0
(-6595 2882);
DISPLAY 0.340426 (-6595 2882);
PAINT GREEN (-6595 2882);
DISPLAY INVISIBLE (-6595 2882);
FORCEPROP 1 LAST HDL_POWER P3V3_STBY
J 0
(-6850 2800);
DISPLAY 0.872340 (-6850 2800);
PAINT ORANGE (-6850 2800);
DISPLAY INVISIBLE (-6850 2800);
FORCEPROP 2 LAST CDS_LIB mstr_symbols
J 0
(-6550 2925);
PAINT MONO (-6550 2925);
DISPLAY INVISIBLE (-6550 2925);
FORCEPROP 1 LAST VOLTAGE 3.3V
J 0
(-6595 2882);
DISPLAY 0.340426 (-6595 2882);
PAINT GREEN (-6595 2882);
DISPLAY INVISIBLE (-6595 2882);
FORCEADD HCB1608KF-800T30-GP..1
R 1
(-6275 2775);
FORCEPROP 1 LAST LOCATION FB2T4
J 0
(-6350 2825);
DISPLAY 0.617021 (-6350 2825);
PAINT GREEN (-6350 2825);
FORCEPROP 1 LAST VALUE HCB1608KF-800T30-GP
J 0
(-6375 2700);
DISPLAY 0.617021 (-6375 2700);
PAINT GREEN (-6375 2700);
FORCEPROP 1 LAST PATH I84
R 1
J 0
(-6275 2775);
DISPLAY 0.617021 (-6275 2775);
PAINT GREEN (-6275 2775);
DISPLAY INVISIBLE (-6275 2775);
FORCEPROP 2 LAST CDS_LIB w_hdl
J 0
(-6275 2775);
PAINT MONO (-6275 2775);
DISPLAY INVISIBLE (-6275 2775);
FORCEPROP 1 LAST CDS_LMAN_SYM_OUTLINE -50,100,50,-100
R 1
J 0
(-6275 2775);
DISPLAY 0.468085 (-6275 2775);
PAINT GREEN (-6275 2775);
DISPLAY INVISIBLE (-6275 2775);
FORCEPROP 1 LAST PACK_TYPE DISCRET-G9
R 1
J 0
(-6275 2775);
DISPLAY 0.617021 (-6275 2775);
PAINT GREEN (-6275 2775);
DISPLAY INVISIBLE (-6275 2775);
FORCEPROP 1 LAST PART_NUMBER 68.00230.231
R 1
J 0
(-6275 2775);
DISPLAY 0.617021 (-6275 2775);
PAINT GREEN (-6275 2775);
DISPLAY INVISIBLE (-6275 2775);
FORCEADD SCD1U16V2KX-3GP..1
(-5175 1400);
FORCEPROP 1 LAST VALUE SCD1U16V2KX-3GP
J 0
(-5150 1350);
DISPLAY 0.617021 (-5150 1350);
PAINT GREEN (-5150 1350);
FORCEPROP 1 LAST LOCATION C25W58
J 0
(-5150 1430);
DISPLAY 0.617021 (-5150 1430);
PAINT GREEN (-5150 1430);
FORCEPROP 1 LAST PATH I85
J 0
(-5175 1400);
DISPLAY 0.617021 (-5175 1400);
PAINT GREEN (-5175 1400);
DISPLAY INVISIBLE (-5175 1400);
FORCEPROP 2 LAST CDS_LIB w_hdl
J 0
(-5175 1400);
PAINT MONO (-5175 1400);
DISPLAY INVISIBLE (-5175 1400);
FORCEPROP 1 LAST CDS_LMAN_SYM_OUTLINE -50,25,50,-25
J 0
(-5175 1400);
DISPLAY 0.468085 (-5175 1400);
PAINT GREEN (-5175 1400);
DISPLAY INVISIBLE (-5175 1400);
FORCEPROP 1 LAST PART_NUMBER 78.10421.2FL
J 0
(-5175 1400);
DISPLAY 0.617021 (-5175 1400);
PAINT GREEN (-5175 1400);
DISPLAY INVISIBLE (-5175 1400);
FORCEPROP 1 LAST PACK_TYPE SMD-BCG
J 0
(-5175 1400);
DISPLAY 0.617021 (-5175 1400);
PAINT GREEN (-5175 1400);
DISPLAY INVISIBLE (-5175 1400);
FORCEADD CAP..1
(-5475 1375);
FORCEPROP 1 LAST LOCATION C25W57
J 0
(-5425 1475);
DISPLAY 0.617021 (-5425 1475);
PAINT AQUA (-5425 1475);
FORCEPROP 1 LAST VALUE 1.0UF
J 0
(-5425 1400);
DISPLAY 0.617021 (-5425 1400);
PAINT SKYBLUE (-5425 1400);
FORCEPROP 1 LAST VOLTAGE 6.3V
J 0
(-5425 1325);
DISPLAY 0.617021 (-5425 1325);
PAINT SKYBLUE (-5425 1325);
FORCEPROP 1 LAST TOLERANCE 10%
J 0
(-5425 1275);
DISPLAY 0.617021 (-5425 1275);
PAINT SKYBLUE (-5425 1275);
FORCEPROP 1 LAST MATERIAL X6S
J 0
(-5425 1225);
DISPLAY 0.617021 (-5425 1225);
PAINT SKYBLUE (-5425 1225);
FORCEPROP 1 LAST PART_NUMBER D97712-004
R 1
J 0
(-5525 1175);
DISPLAY 0.617021 (-5525 1175);
PAINT BLUE (-5525 1175);
FORCEPROP 1 LAST PACK_TYPE 0402
J 0
(-5425 1175);
DISPLAY 0.617021 (-5425 1175);
PAINT SKYBLUE (-5425 1175);
FORCEPROP 1 LAST PATH I86
J 0
(-5425 1525);
DISPLAY 0.978723 (-5425 1525);
PAINT WHITE (-5425 1525);
DISPLAY INVISIBLE (-5425 1525);
FORCEPROP 2 LAST CDS_LIB mstr_discrete
J 0
(-5475 1375);
PAINT MONO (-5475 1375);
DISPLAY INVISIBLE (-5475 1375);
FORCEPROP 2 LAST ROOM BMC
J 0
(-5425 1525);
DISPLAY 1.510638 (-5425 1525);
PAINT ORANGE (-5425 1525);
DISPLAY INVISIBLE (-5425 1525);
FORCEPROP 2 LAST BOM_COST SM_CONTROLLER
J 0
(-5425 1525);
PAINT MONO (-5425 1525);
DISPLAY INVISIBLE (-5425 1525);
FORCEPROP 1 LASTPIN (-5475 1275) $PN 2
J 0
(-5465 1255);
DISPLAY 0.787234 (-5465 1255);
PAINT ORANGE (-5465 1255);
DISPLAY INVISIBLE (-5465 1255);
FORCEPROP 1 LASTPIN (-5475 1475) $PN 1
J 0
(-5465 1455);
DISPLAY 0.787234 (-5465 1455);
PAINT ORANGE (-5465 1455);
DISPLAY INVISIBLE (-5465 1455);
FORCEADD CAP..1
(-5725 1375);
FORCEPROP 1 LAST MATERIAL X6S
J 0
(-5675 1225);
DISPLAY 0.617021 (-5675 1225);
PAINT SKYBLUE (-5675 1225);
FORCEPROP 1 LAST VOLTAGE 6.3V
J 0
(-5675 1325);
DISPLAY 0.617021 (-5675 1325);
PAINT SKYBLUE (-5675 1325);
FORCEPROP 1 LAST VALUE 1.0UF
J 0
(-5675 1400);
DISPLAY 0.617021 (-5675 1400);
PAINT SKYBLUE (-5675 1400);
FORCEPROP 1 LAST LOCATION C25W56
J 0
(-5675 1475);
DISPLAY 0.617021 (-5675 1475);
PAINT AQUA (-5675 1475);
FORCEPROP 1 LAST PART_NUMBER D97712-004
R 1
J 0
(-5775 1175);
DISPLAY 0.617021 (-5775 1175);
PAINT BLUE (-5775 1175);
FORCEPROP 1 LAST TOLERANCE 10%
J 0
(-5675 1275);
DISPLAY 0.617021 (-5675 1275);
PAINT SKYBLUE (-5675 1275);
FORCEPROP 1 LAST PACK_TYPE 0402
J 0
(-5675 1175);
DISPLAY 0.617021 (-5675 1175);
PAINT SKYBLUE (-5675 1175);
FORCEPROP 1 LAST PATH I87
J 0
(-5675 1525);
DISPLAY 0.978723 (-5675 1525);
PAINT WHITE (-5675 1525);
DISPLAY INVISIBLE (-5675 1525);
FORCEPROP 2 LAST CDS_LIB mstr_discrete
J 0
(-5725 1375);
PAINT MONO (-5725 1375);
DISPLAY INVISIBLE (-5725 1375);
FORCEPROP 2 LAST ROOM BMC
J 0
(-5675 1525);
DISPLAY 1.510638 (-5675 1525);
PAINT ORANGE (-5675 1525);
DISPLAY INVISIBLE (-5675 1525);
FORCEPROP 2 LAST BOM_COST SM_CONTROLLER
J 0
(-5675 1525);
PAINT MONO (-5675 1525);
DISPLAY INVISIBLE (-5675 1525);
FORCEPROP 1 LASTPIN (-5725 1275) $PN 2
J 0
(-5715 1255);
DISPLAY 0.787234 (-5715 1255);
PAINT ORANGE (-5715 1255);
DISPLAY INVISIBLE (-5715 1255);
FORCEPROP 1 LASTPIN (-5725 1475) $PN 1
J 0
(-5715 1455);
DISPLAY 0.787234 (-5715 1455);
PAINT ORANGE (-5715 1455);
DISPLAY INVISIBLE (-5715 1455);
FORCEADD P3V3_STBY..1
(-6550 1875);
FORCEPROP 3 LASTPIN (-6550 1825) SIG_NAME P3V3_STBY\g
J 0
(-6540 1835);
DISPLAY 0.659574 (-6540 1835);
PAINT MONO (-6540 1835);
DISPLAY INVISIBLE (-6540 1835);
FORCEPROP 1 LAST PATH I88
J 0
(-6505 1877);
DISPLAY 0.340426 (-6505 1877);
PAINT GREEN (-6505 1877);
DISPLAY INVISIBLE (-6505 1877);
FORCEPROP 1 LAST HDL_POWER P3V3_STBY
J 0
(-6850 1750);
DISPLAY 0.872340 (-6850 1750);
PAINT ORANGE (-6850 1750);
DISPLAY INVISIBLE (-6850 1750);
FORCEPROP 1 LAST BODY_TYPE PLUMBING
J 0
(-6595 1832);
DISPLAY 0.340426 (-6595 1832);
PAINT GREEN (-6595 1832);
DISPLAY INVISIBLE (-6595 1832);
FORCEPROP 1 LAST SIZE 1B
J 0
(-6505 1897);
DISPLAY 0.340426 (-6505 1897);
PAINT GREEN (-6505 1897);
DISPLAY INVISIBLE (-6505 1897);
FORCEPROP 2 LAST CDS_LIB mstr_symbols
J 0
(-6550 1875);
PAINT MONO (-6550 1875);
DISPLAY INVISIBLE (-6550 1875);
FORCEPROP 1 LAST VOLTAGE 3.3V
J 0
(-6595 1832);
DISPLAY 0.340426 (-6595 1832);
PAINT GREEN (-6595 1832);
DISPLAY INVISIBLE (-6595 1832);
FORCEADD HCB1608KF-800T30-GP..1
R 1
(-6250 1725);
FORCEPROP 1 LAST VALUE HCB1608KF-800T30-GP
J 0
(-6350 1650);
DISPLAY 0.617021 (-6350 1650);
PAINT GREEN (-6350 1650);
FORCEPROP 1 LAST LOCATION FB2T5
J 0
(-6325 1775);
DISPLAY 0.617021 (-6325 1775);
PAINT GREEN (-6325 1775);
FORCEPROP 1 LAST PATH I89
R 1
J 0
(-6250 1725);
DISPLAY 0.617021 (-6250 1725);
PAINT GREEN (-6250 1725);
DISPLAY INVISIBLE (-6250 1725);
FORCEPROP 1 LAST PART_NUMBER 68.00230.231
R 1
J 0
(-6250 1725);
DISPLAY 0.617021 (-6250 1725);
PAINT GREEN (-6250 1725);
DISPLAY INVISIBLE (-6250 1725);
FORCEPROP 1 LAST PACK_TYPE DISCRET-G9
R 1
J 0
(-6250 1725);
DISPLAY 0.617021 (-6250 1725);
PAINT GREEN (-6250 1725);
DISPLAY INVISIBLE (-6250 1725);
FORCEPROP 2 LAST CDS_LIB w_hdl
J 0
(-6250 1725);
PAINT MONO (-6250 1725);
DISPLAY INVISIBLE (-6250 1725);
FORCEPROP 1 LAST CDS_LMAN_SYM_OUTLINE -50,100,50,-100
R 1
J 0
(-6250 1725);
DISPLAY 0.468085 (-6250 1725);
PAINT GREEN (-6250 1725);
DISPLAY INVISIBLE (-6250 1725);
FORCEADD W_VCC_CIRCLE..1
(-500 4025);
FORCEPROP 3 LASTPIN (-500 4025) SIG_NAME VCC_A_1V1\g
J 0
(-490 4035);
DISPLAY 0.659574 (-490 4035);
PAINT MONO (-490 4035);
DISPLAY INVISIBLE (-490 4035);
FORCEPROP 1 LAST HDL_POWER VCC_A_1V1
J 1
(-479 4100);
DISPLAY 0.872340 (-479 4100);
PAINT ORANGE (-479 4100);
FORCEPROP 1 LAST PATH I9
J 0
(-500 4025);
DISPLAY 0.617021 (-500 4025);
PAINT GREEN (-500 4025);
DISPLAY INVISIBLE (-500 4025);
FORCEPROP 1 LAST CDS_LMAN_SYM_OUTLINE -100,100,100,-100
J 0
(-500 4025);
DISPLAY 0.468085 (-500 4025);
PAINT GREEN (-500 4025);
DISPLAY INVISIBLE (-500 4025);
FORCEPROP 2 LAST CDS_LIB w_power
J 0
(-500 4025);
PAINT MONO (-500 4025);
DISPLAY INVISIBLE (-500 4025);
FORCEPROP 1 LAST BODY_TYPE PLUMBING
J 0
(-488 4019);
DISPLAY 0.340426 (-488 4019);
PAINT GREEN (-488 4019);
DISPLAY INVISIBLE (-488 4019);
FORCEADD INTEL_CORP_BPAGE..1
(1150 575);
FORCEPROP 1 LAST CDS_CON_LAST_MODIFIED Tue Dec 01 11:52:07 2015
J 0
(-275 900);
DISPLAY 1.361702 (-275 900);
PAINT GREEN (-275 900);
DISPLAY INVISIBLE (-275 900);
FORCEPROP 1 LAST CUSTOM_TXT_CDS <CURRENT_DESIGN_SHEET> OF <TOTAL_DESIGN_SHEETS>
J 0
(650 600);
PAINT GREEN (650 600);
FORCEPROP 1 LAST CUSTOM_TXT_CDS <CON_LAST_MODIFIED>
J 0
(-775 925);
PAINT GREEN (-775 925);
FORCEPROP 2 LAST CUSTOM_TXT_CDS <XR_PAGE_TITLE>
J 0
(-6740 5825);
DISPLAY 0.638298 (-6740 5825);
PAINT PINK (-6740 5825);
DISPLAY INVISIBLE (-6740 5825);
FORCEPROP 1 LAST SCH_TITLE BMC DECOUPLING CAPS
J 0
(-6800 625);
DISPLAY 1.212766 (-6800 625);
PAINT ORANGE (-6800 625);
FORCEPROP 1 LAST SCH_REV 2.420
J 0
(900 725);
DISPLAY 0.978723 (900 725);
PAINT YELLOW (900 725);
FORCEPROP 1 LAST SCH_NUMBER H4694802
J 0
(-150 725);
DISPLAY 1.212766 (-150 725);
PAINT YELLOW (-150 725);
FORCEPROP 1 LAST SCH_ADDRESS3 Santa Clara, CA 95052-8119
J 0
(-2825 600);
DISPLAY 0.617021 (-2825 600);
PAINT GREEN (-2825 600);
FORCEPROP 1 LAST SCH_ADDRESS2 P.O. BOX 58119
J 0
(-2825 650);
DISPLAY 0.617021 (-2825 650);
PAINT GREEN (-2825 650);
FORCEPROP 1 LAST SCH_ADDRESS1 2200 Mission College Blvd.
J 0
(-2825 700);
DISPLAY 0.617021 (-2825 700);
PAINT GREEN (-2825 700);
FORCEPROP 1 LAST SCH_DEPT BESD
J 1
(-3300 675);
DISPLAY 1.212766 (-3300 675);
PAINT YELLOW (-3300 675);
FORCEPROP 2 LAST PAGE_BORDER TRUE
J 0
(-6740 5825);
DISPLAY 0.851064 (-6740 5825);
PAINT PINK (-6740 5825);
DISPLAY INVISIBLE (-6740 5825);
FORCEPROP 2 LAST CDS_LIB mstr_symbols
J 0
(1150 575);
DISPLAY 1.361702 (1150 575);
PAINT ORANGE (1150 575);
DISPLAY INVISIBLE (1150 575);
FORCEPROP 1 LAST COMMENT_BODY TRUE
J 0
(1162 587);
DISPLAY 0.617021 (1162 587);
PAINT GREEN (1162 587);
DISPLAY INVISIBLE (1162 587);
FORCEPROP 2 LAST CDS_XR_PAGE_TITLE CR-150 : @BASEBOARD_FAB2_LIB.BASEBOARD_FAB2(SCH_1):PAGE150
J 0
(-6740 5825);
DISPLAY 0.638298 (-6740 5825);
PAINT PINK (-6740 5825);
DISPLAY INVISIBLE (-6740 5825);
WIRE 16 -1 (-275 2375)(-275 2225);
WIRE 16 -1 (-275 2225)(25 2225);
WIRE 16 -1 (25 2375)(25 2225);
WIRE 16 -1 (25 2225)(275 2225);
WIRE 16 -1 (275 2375)(275 2225);
WIRE 16 -1 (275 2225)(525 2225);
WIRE 16 -1 (525 2375)(525 2225);
WIRE 16 -1 (525 2225)(775 2225);
WIRE 16 -1 (775 2425)(775 2225);
WIRE 16 -1 (775 2125)(775 2225);
WIRE 16 -1 (775 2675)(775 2575);
WIRE 16 -1 (525 2675)(775 2675);
WIRE 16 -1 (525 2575)(525 2675);
WIRE 16 -1 (275 2675)(525 2675);
WIRE 16 -1 (275 2575)(275 2675);
WIRE 16 -1 (25 2675)(275 2675);
WIRE 16 -1 (25 2575)(25 2675);
WIRE 16 -1 (-275 2675)(25 2675);
WIRE 16 -1 (-275 2575)(-275 2675);
WIRE 16 -1 (-275 2675)(-275 2925);
WIRE 16 -1 (-1450 3425)(-1450 3225);
WIRE 16 -1 (-900 3225)(-1450 3225);
WIRE 16 -1 (-900 3475)(-900 3225);
WIRE 16 -1 (-900 3225)(-500 3225);
WIRE 16 -1 (-500 3225)(-500 3475);
WIRE 16 -1 (650 1775)(650 1525);
WIRE 16 -1 (650 1775)(250 1775);
WIRE 16 -1 (250 1525)(250 1775);
WIRE 16 -1 (250 1775)(-300 1775);
WIRE 16 -1 (-300 1925)(-300 1775);
WIRE 16 -1 (-300 1775)(-300 1525);
WIRE 16 -1 (-700 1775)(-300 1775);
WIRE 16 -1 (-1900 2450)(-1900 2250);
WIRE 16 -1 (-1350 2250)(-1900 2250);
WIRE 16 -1 (-1350 2500)(-1350 2250);
WIRE 16 -1 (-1350 2250)(-950 2250);
WIRE 16 -1 (-950 2250)(-950 2500);
WIRE 16 -1 (-300 1325)(-300 1125);
WIRE 16 -1 (-300 1125)(250 1125);
WIRE 16 -1 (250 1375)(250 1125);
WIRE 16 -1 (250 1125)(650 1125);
WIRE 16 -1 (650 1125)(650 1375);
WIRE 16 -1 (650 1025)(650 1125);
WIRE 16 -1 (-1825 5075)(-2075 5075);
WIRE 16 -1 (-1825 4825)(-1825 5075);
WIRE 16 -1 (-1525 5075)(-1825 5075);
WIRE 16 -1 (-2075 5075)(-2075 4825);
WIRE 16 -1 (-2575 5075)(-2075 5075);
WIRE 16 -1 (-1525 4825)(-1525 5075);
WIRE 16 -1 (-1125 5075)(-1525 5075);
WIRE 16 -1 (-1125 5225)(-1125 5075);
WIRE 16 -1 (-1125 5075)(-1125 4825);
WIRE 16 -1 (-2075 4625)(-2075 4425);
WIRE 16 -1 (-2075 4425)(-1825 4425);
WIRE 16 -1 (-1825 4625)(-1825 4425);
WIRE 16 -1 (-1825 4425)(-1525 4425);
WIRE 16 -1 (-1525 4675)(-1525 4425);
WIRE 16 -1 (-1525 4425)(-1125 4425);
WIRE 16 -1 (-1125 4425)(-1125 4675);
WIRE 16 -1 (-1125 4325)(-1125 4425);
WIRE 16 -1 (25 5075)(75 5075);
WIRE 16 -1 (75 5075)(575 5075);
WIRE 16 -1 (75 4950)(75 5075);
WIRE 16 -1 (575 5175)(575 5075);
WIRE 16 -1 (575 5075)(575 5000);
WIRE 16 -1 (-2200 3875)(-2050 3875);
WIRE 16 -1 (-2200 3975)(-2200 3875);
WIRE 16 -1 (-1100 1775)(-1000 1775);
WIRE 16 -1 (-1100 1900)(-1100 1775);
WIRE 16 -1 (-950 2900)(-950 2650);
WIRE 16 -1 (-950 2900)(-1350 2900);
WIRE 16 -1 (-1350 2650)(-1350 2900);
WIRE 16 -1 (-1350 2900)(-1900 2900);
WIRE 16 -1 (-1900 2900)(-1900 2650);
WIRE 16 -1 (-1900 2900)(-2650 2900);
WIRE 16 -1 (-2650 3000)(-2650 2900);
WIRE 16 -1 (-3025 5175)(-3025 5075);
WIRE 16 -1 (-3025 5075)(-2875 5075);
WIRE 16 -1 (-3800 3650)(-3800 3850);
WIRE 16 -1 (-3800 3850)(-3450 3850);
WIRE 16 -1 (-3950 3850)(-3800 3850);
WIRE 16 -1 (-3450 3700)(-3450 3850);
WIRE 16 -1 (-3450 3850)(-3100 3850);
WIRE 16 -1 (-3100 3675)(-3100 3850);
WIRE 16 -1 (-3100 4025)(-3100 3850);
WIRE 16 -1 (-6475 4875)(-6475 4700);
WIRE 16 -1 (-6475 4700)(-6075 4700);
WIRE 16 -1 (-6075 4875)(-6075 4700);
WIRE 16 -1 (-6075 4700)(-5675 4700);
WIRE 16 -1 (-5675 4875)(-5675 4700);
WIRE 16 -1 (-5675 4700)(-5275 4700);
WIRE 16 -1 (-5275 4875)(-5275 4700);
WIRE 16 -1 (-5275 4700)(-4875 4700);
WIRE 16 -1 (-4875 4875)(-4875 4700);
WIRE 16 -1 (-4875 4700)(-4475 4700);
WIRE 16 -1 (-4475 4875)(-4475 4700);
WIRE 16 -1 (-4475 4700)(-4075 4700);
WIRE 16 -1 (-4075 4875)(-4075 4700);
WIRE 16 -1 (-4075 4700)(-3675 4700);
WIRE 16 -1 (-3675 4700)(-3675 4900);
WIRE 16 -1 (-3675 4700)(-3675 4550);
WIRE 16 -1 (-4200 3850)(-4400 3850);
WIRE 16 -1 (-4400 3850)(-4400 3950);
WIRE 16 -1 (-5700 3775)(-5700 3975);
WIRE 16 -1 (-5250 3975)(-5700 3975);
WIRE 16 -1 (-6150 3975)(-5700 3975);
WIRE 16 -1 (-5250 3825)(-5250 3975);
WIRE 16 -1 (-5250 3975)(-4900 3975);
WIRE 16 -1 (-4900 3800)(-4900 3975);
WIRE 16 -1 (-4900 4050)(-4900 3975);
WIRE 16 -1 (75 4800)(75 4575);
WIRE 16 -1 (75 4575)(575 4575);
WIRE 16 -1 (575 4800)(575 4575);
WIRE 16 -1 (575 4575)(575 4525);
WIRE 16 -1 (-3800 3500)(-3800 3250);
WIRE 16 -1 (-3450 3250)(-3800 3250);
WIRE 16 -1 (-3450 3500)(-3450 3250);
WIRE 16 -1 (-3450 3250)(-3100 3250);
WIRE 16 -1 (-3100 3250)(-3100 3525);
WIRE 16 -1 (-3100 3250)(-3100 3100);
WIRE 16 -1 (-5675 2375)(-5675 2175);
WIRE 16 -1 (-5675 2175)(-5375 2175);
WIRE 16 -1 (-5375 2375)(-5375 2175);
WIRE 16 -1 (-5375 2175)(-5125 2175);
WIRE 16 -1 (-5125 2375)(-5125 2175);
WIRE 16 -1 (-5125 2175)(-4875 2175);
WIRE 16 -1 (-4575 2175)(-4875 2175);
WIRE 16 -1 (-4875 2175)(-4875 2375);
WIRE 16 -1 (-4575 2375)(-4575 2175);
WIRE 16 -1 (-4325 2175)(-4575 2175);
WIRE 16 -1 (-4325 2425)(-4325 2175);
WIRE 16 -1 (-3975 2175)(-4325 2175);
WIRE 16 -1 (-3975 2375)(-3975 2175);
WIRE 16 -1 (-3750 2175)(-3975 2175);
WIRE 16 -1 (-3750 2175)(-3675 2175);
WIRE 16 -1 (-3750 2025)(-3750 2175);
WIRE 16 -1 (-3675 2175)(-3675 2425);
WIRE 16 -1 (-5675 2575)(-5675 2775);
WIRE 16 -1 (-5675 2775)(-5375 2775);
WIRE 16 -1 (-6125 2775)(-5675 2775);
WIRE 16 -1 (-5375 2575)(-5375 2775);
WIRE 16 -1 (-5375 2775)(-5125 2775);
WIRE 16 -1 (-5125 2575)(-5125 2775);
WIRE 16 -1 (-5125 2775)(-4875 2775);
WIRE 16 -1 (-4875 2575)(-4875 2775);
WIRE 16 -1 (-4875 2775)(-4575 2775);
WIRE 16 -1 (-4575 2575)(-4575 2775);
WIRE 16 -1 (-4575 2775)(-4325 2775);
WIRE 16 -1 (-4325 2775)(-3975 2775);
WIRE 16 -1 (-4325 2575)(-4325 2775);
WIRE 16 -1 (-4325 2925)(-4325 2775);
WIRE 16 -1 (-3975 2775)(-3675 2775);
WIRE 16 -1 (-3975 2575)(-3975 2775);
WIRE 16 -1 (-3675 2775)(-3675 2575);
WIRE 16 -1 (-5700 3625)(-5700 3375);
WIRE 16 -1 (-5250 3375)(-5700 3375);
WIRE 16 -1 (-5250 3625)(-5250 3375);
WIRE 16 -1 (-5250 3375)(-4900 3375);
WIRE 16 -1 (-4900 3375)(-4900 3600);
WIRE 16 -1 (-4900 3375)(-4900 3225);
WIRE 16 -1 (-5475 1725)(-5725 1725);
WIRE 16 -1 (-5475 1475)(-5475 1725);
WIRE 16 -1 (-5175 1725)(-5475 1725);
WIRE 16 -1 (-6100 1725)(-5725 1725);
WIRE 16 -1 (-5725 1725)(-5725 1475);
WIRE 16 -1 (-5175 1475)(-5175 1725);
WIRE 16 -1 (-4775 1725)(-5175 1725);
WIRE 16 -1 (-4775 1875)(-4775 1725);
WIRE 16 -1 (-4775 1725)(-4775 1475);
WIRE 16 -1 (-2750 1200)(-2750 1000);
WIRE 16 -1 (-2200 1000)(-2750 1000);
WIRE 16 -1 (-2200 1250)(-2200 1000);
WIRE 16 -1 (-2200 1000)(-1800 1000);
WIRE 16 -1 (-1800 1000)(-1800 1250);
WIRE 16 -1 (-1800 1650)(-1800 1400);
WIRE 16 -1 (-1800 1650)(-2200 1650);
WIRE 16 -1 (-2200 1400)(-2200 1650);
WIRE 16 -1 (-2200 1650)(-2750 1650);
WIRE 16 -1 (-2750 1650)(-2750 1400);
WIRE 16 -1 (-2750 1650)(-3500 1650);
WIRE 16 -1 (-3500 1750)(-3500 1650);
WIRE 16 -1 (-5725 1275)(-5725 1075);
WIRE 16 -1 (-5725 1075)(-5475 1075);
WIRE 16 -1 (-5475 1275)(-5475 1075);
WIRE 16 -1 (-5475 1075)(-5175 1075);
WIRE 16 -1 (-5175 1325)(-5175 1075);
WIRE 16 -1 (-5175 1075)(-4775 1075);
WIRE 16 -1 (-4775 1075)(-4775 1325);
WIRE 16 -1 (-4775 975)(-4775 1075);
WIRE 16 -1 (-4075 5150)(-3675 5150);
WIRE 16 -1 (-4075 5150)(-4075 5075);
WIRE 16 -1 (-4475 5150)(-4075 5150);
WIRE 16 -1 (-3675 5150)(-3675 5050);
WIRE 16 -1 (-4875 5150)(-4475 5150);
WIRE 16 -1 (-4475 5150)(-4475 5075);
WIRE 16 -1 (-4875 5150)(-4875 5075);
WIRE 16 -1 (-5275 5150)(-4875 5150);
WIRE 16 -1 (-5675 5150)(-5275 5150);
WIRE 16 -1 (-5275 5150)(-5275 5075);
WIRE 16 -1 (-6075 5150)(-5675 5150);
WIRE 16 -1 (-5675 5150)(-5675 5075);
WIRE 16 -1 (-6075 5150)(-6075 5075);
WIRE 16 -1 (-6475 5150)(-6075 5150);
WIRE 16 -1 (-6475 5075)(-6475 5150);
WIRE 16 -1 (-6475 5150)(-6475 5200);
WIRE 16 -1 (-6575 3975)(-6450 3975);
WIRE 16 -1 (-6575 4075)(-6575 3975);
WIRE 16 -1 (-225 5075)(-425 5075);
WIRE 16 -1 (-425 5075)(-425 5175);
WIRE 16 -1 (-6550 2775)(-6425 2775);
WIRE 16 -1 (-6550 2875)(-6550 2775);
WIRE 16 -1 (-6550 1725)(-6400 1725);
WIRE 16 -1 (-6550 1825)(-6550 1725);
WIRE 16 -1 (-900 3875)(-1450 3875);
WIRE 16 -1 (-900 3625)(-900 3875);
WIRE 16 -1 (-500 3875)(-900 3875);
WIRE 16 -1 (-1450 3875)(-1450 3625);
WIRE 16 -1 (-1750 3875)(-1450 3875);
WIRE 16 -1 (-500 4025)(-500 3875);
WIRE 16 -1 (-500 3875)(-500 3625);
WIRE 16 2175 (-6600 5175)(-4700 5175);
WIRE 16 2175 (-6600 4625)(-6600 5175);
WIRE 16 2175 (-4700 4625)(-4700 5175);
WIRE 16 2175 (-6600 4625)(-4700 4625);
WIRE 16 2175 (-4550 5175)(-3325 5175);
WIRE 16 2175 (-4550 4600)(-4550 5175);
WIRE 16 2175 (-3325 4600)(-3325 5175);
WIRE 16 2175 (-4550 4600)(-3325 4600);
WIRE 16 2175 (-5775 2075)(-4475 2075);
WIRE 16 2175 (-5775 2075)(-5775 2825);
WIRE 16 2175 (-4475 2075)(-4475 2825);
WIRE 16 2175 (-5775 2825)(-4475 2825);
WIRE 16 2175 (-4375 2825)(-3300 2825);
WIRE 16 2175 (-4375 2100)(-4375 2825);
WIRE 16 2175 (-3300 2100)(-3300 2825);
WIRE 16 2175 (-4375 2100)(-3300 2100);
DOT 1 (-5725 1725);
DOT 1 (-5475 1075);
DOT 1 (-5175 1075);
DOT 1 (-5475 1725);
DOT 1 (-5175 1725);
DOT 1 (-5675 2775);
DOT 1 (-5375 2175);
DOT 1 (-5125 2175);
DOT 1 (-5375 2775);
DOT 1 (-5125 2775);
DOT 1 (-5250 3375);
DOT 1 (-6475 5150);
DOT 1 (-5700 3975);
DOT 1 (-6075 4700);
DOT 1 (-5675 4700);
DOT 1 (-5250 3975);
DOT 1 (-5275 4700);
DOT 1 (-6075 5150);
DOT 1 (-5675 5150);
DOT 1 (-5275 5150);
DOT 1 (-4775 1075);
DOT 1 (-4775 1725);
DOT 1 (-2750 1650);
DOT 1 (-2200 1000);
DOT 1 (-2200 1650);
DOT 1 (-4875 2175);
DOT 1 (-4875 2775);
DOT 1 (-4575 2175);
DOT 1 (-4325 2175);
DOT 1 (-4575 2775);
DOT 1 (-4325 2775);
DOT 1 (-4900 3375);
DOT 1 (-3975 2175);
DOT 1 (-3750 2175);
DOT 1 (-3975 2775);
DOT 1 (-3800 3850);
DOT 1 (-3450 3250);
DOT 1 (-3100 3250);
DOT 1 (-3450 3850);
DOT 1 (-3100 3850);
DOT 1 (-4900 3975);
DOT 1 (-4875 4700);
DOT 1 (-4475 4700);
DOT 1 (-4875 5150);
DOT 1 (-4475 5150);
DOT 1 (-4075 4700);
DOT 1 (-3675 4700);
DOT 1 (-4075 5150);
DOT 1 (-1350 2250);
DOT 1 (-1900 2900);
DOT 1 (-1350 2900);
DOT 1 (-1450 3875);
DOT 1 (-2075 5075);
DOT 1 (-1825 4425);
DOT 1 (-1525 4425);
DOT 1 (-1125 4425);
DOT 1 (-1825 5075);
DOT 1 (-1525 5075);
DOT 1 (-1125 5075);
DOT 1 (-300 1775);
DOT 1 (250 1125);
DOT 1 (250 1775);
DOT 1 (650 1125);
DOT 1 (-275 2675);
DOT 1 (-900 3225);
DOT 1 (-900 3875);
DOT 1 (-500 3875);
DOT 1 (25 2225);
DOT 1 (275 2225);
DOT 1 (25 2675);
DOT 1 (275 2675);
DOT 1 (525 2675);
DOT 1 (525 2225);
DOT 1 (775 2225);
DOT 1 (575 4575);
DOT 1 (75 5075);
DOT 1 (575 5075);
FORCENOTE
PLACEMENT CLOSE K5,K6 PIN  OR  POWER  PLANE
(-4250 4200) 0;
DISPLAY LEFT (-4250 4200);
DISPLAY 1.021277 (-4250 4200);
PAINT PURPLE (-4250 4200);
FORCENOTE
PLACEMENT CLOSE K17,F13,F12 PIN  OR  POWER  PLANE
(-6050 2875) 0;
DISPLAY LEFT (-6050 2875);
DISPLAY 1.021277 (-6050 2875);
PAINT PURPLE (-6050 2875);
FORCENOTE
PLACEMENT CLOSE CHIP
(-4125 2900) 0;
DISPLAY LEFT (-4125 2900);
DISPLAY 1.021277 (-4125 2900);
PAINT PURPLE (-4125 2900);
FORCENOTE
0.08 OHM@100MHZ 3A
(-6650 1550) 0;
DISPLAY LEFT (-6650 1550);
DISPLAY 1.021277 (-6650 1550);
PAINT PURPLE (-6650 1550);
FORCENOTE
ROOM=SM_CONTROLLER
(-6608 898) 0;
DISPLAY LEFT (-6608 898);
DISPLAY 0.617021 (-6608 898);
PAINT PURPLE (-6608 898);
FORCENOTE
0.08 OHM@100MHZ 3A
(-6675 3800) 0;
DISPLAY LEFT (-6675 3800);
DISPLAY 1.021277 (-6675 3800);
PAINT PURPLE (-6675 3800);
FORCENOTE
0.08 OHM@100MHZ 3A
(-6600 2600) 0;
DISPLAY LEFT (-6600 2600);
DISPLAY 1.021277 (-6600 2600);
PAINT PURPLE (-6600 2600);
FORCENOTE
PLACEMENT CLOSE J6  PIN  OR  POWER  PLANE
(-6000 4000) 0;
DISPLAY LEFT (-6000 4000);
DISPLAY 1.021277 (-6000 4000);
PAINT PURPLE (-6000 4000);
FORCENOTE
PLACEMENT CLOSE Y17,W17 PIN OR POWER PLANE
(-6075 1800) 0;
DISPLAY LEFT (-6075 1800);
DISPLAY 1.021277 (-6075 1800);
PAINT PURPLE (-6075 1800);
FORCENOTE
PLACEMENT CLOSE F10,F11,F7,F8 PIN OR POWER PLANE
(-3375 1700) 0;
DISPLAY LEFT (-3375 1700);
DISPLAY 1.021277 (-3375 1700);
PAINT PURPLE (-3375 1700);
FORCENOTE
0.08 OHM@100MHZ 3A
(-2300 3725) 0;
DISPLAY LEFT (-2300 3725);
DISPLAY 1.021277 (-2300 3725);
PAINT PURPLE (-2300 3725);
FORCENOTE
0.08 OHM@100MHZ 3A
(-3025 4925) 0;
DISPLAY LEFT (-3025 4925);
DISPLAY 1.021277 (-3025 4925);
PAINT PURPLE (-3025 4925);
FORCENOTE
PLACEMENT CLOSE J17,K17 PIN OR POWER PLANE
(-2350 2975) 0;
DISPLAY LEFT (-2350 2975);
DISPLAY 1.021277 (-2350 2975);
PAINT PURPLE (-2350 2975);
FORCENOTE
PLACEMENT CLOSE J7,H7 PIN OR POWER PLANE
(-2625 5150) 0;
DISPLAY LEFT (-2625 5150);
DISPLAY 1.021277 (-2625 5150);
PAINT PURPLE (-2625 5150);
FORCENOTE
PLACEMENT CLOSE L5,L6 PIN OR POWER PLANE
(-1850 4000) 0;
DISPLAY LEFT (-1850 4000);
DISPLAY 1.021277 (-1850 4000);
PAINT PURPLE (-1850 4000);
FORCENOTE
PLACEMENT CLOSE L5,L6 PIN OR POWER PLANE
(-625 1825) 0;
DISPLAY LEFT (-625 1825);
DISPLAY 1.021277 (-625 1825);
PAINT PURPLE (-625 1825);
FORCENOTE
PLACEMENT CLOSE T8,10,12,13,14 PIN OR POWER PLANE
(-500 2725) 0;
DISPLAY LEFT (-500 2725);
DISPLAY 1.021277 (-500 2725);
PAINT PURPLE (-500 2725);
FORCENOTE
0.08 OHM@100MHZ 3A
(-1200 1600) 0;
DISPLAY LEFT (-1200 1600);
DISPLAY 1.021277 (-1200 1600);
PAINT PURPLE (-1200 1600);
FORCENOTE
1UF 6.3V NEED CHANGE TO 16V WAIT FOR SYMBOL
(-4150 5450) 0;
DISPLAY LEFT (-4150 5450);
DISPLAY 1.702128 (-4150 5450);
PAINT RED (-4150 5450);
FORCENOTE
PLACEMENT CLOSE CHIP
(-4325 5200) 0;
DISPLAY LEFT (-4325 5200);
DISPLAY 1.021277 (-4325 5200);
PAINT PURPLE (-4325 5200);
FORCENOTE
PLACEMENT CLOSE F6,AA17,G13 AND 1VDD PIN CHIP OR POWER PLANE
(-6425 5200) 0;
DISPLAY LEFT (-6425 5200);
DISPLAY 1.021277 (-6425 5200);
PAINT PURPLE (-6425 5200);
QUIT
